G04 ================== begin FILE IDENTIFICATION RECORD ==================*
G04 Layout Name:  D:/<user>/Wistron_project/16342-2/gbr/16342-2.brd*
G04 Film Name:    DP_REF_L8*
G04 File Format:  Gerber RS274X*
G04 File Origin:  Cadence Allegro 16.5-S056*
G04 Origin Date:  Mon Aug 07 11:25:09 2017*
G04 *
G04 Layer:  BOARD GEOMETRY/DP_REF_L8_TBL*
G04 Layer:  BOARD GEOMETRY/DP_REF_L8_BOTTOM*
G04 Layer:  BOARD GEOMETRY/PANEL_OUTLINE*
G04 *
G04 Offset:    (0.00 0.00)*
G04 Mirror:    No*
G04 Mode:      Positive*
G04 Rotation:  0*
G04 FullContactRelief:  No*
G04 UndefLineWidth:     6.00*
G04 ================== end FILE IDENTIFICATION RECORD ====================*
%FSLAX35Y35*MOIN*%
%IR0*IPPOS*OFA0.00000B0.00000*MIA0B0*SFA1.00000B1.00000*%
%ADD10C,.02*%
%ADD11C,.006*%
%ADD12C,.0049*%
%ADD13C,.00575*%
G75*
%LPD*%
G75*
G54D10*
G01X975497Y625480D02*
X1727997D01*
G01X975497Y729430D02*
Y625480D01*
G01Y694780D02*
X1727997D01*
G01X975497Y660130D02*
X1727997D01*
G01X975497Y729430D02*
X1727997D01*
G01X1150497D02*
Y625480D01*
G01X1412997Y729430D02*
Y625480D01*
G01X1517997Y729430D02*
Y625480D01*
G01X1727997Y729430D02*
Y625480D01*
G54D11*
G01X6250Y-32800D02*
Y-50300D01*
G01X1228Y-32800D02*
X11272D01*
G01X20038Y-50300D02*
Y-32800D01*
G01Y-41258D02*
X21130Y-39800D01*
X22222Y-38925D01*
X23968Y-38634D01*
X25278Y-38925D01*
X26807Y-40092D01*
X27462Y-41842D01*
Y-50300D01*
G01X41250Y-38634D02*
Y-50300D01*
G01Y-33967D02*
X40813Y-33675D01*
Y-33092D01*
X41250Y-32800D01*
X41687Y-33092D01*
Y-33675D01*
X41250Y-33967D01*
G01X55475Y-48259D02*
X56567Y-49425D01*
X58095Y-50300D01*
X59405D01*
X60715Y-49717D01*
X61588Y-48842D01*
X62025Y-47676D01*
X61807Y-45925D01*
X60933Y-45050D01*
X57003Y-43300D01*
X56130Y-41258D01*
X56567Y-39800D01*
X57440Y-38925D01*
X58750Y-38634D01*
X60060Y-38925D01*
X61370Y-39800D01*
G01X90693Y-54675D02*
X92222Y-55842D01*
X93968Y-56133D01*
X95496Y-55842D01*
X96807Y-54384D01*
X97680Y-52342D01*
Y-38634D01*
G01Y-40967D02*
X96807Y-39800D01*
X95496Y-38925D01*
X93968Y-38634D01*
X92222Y-39217D01*
X91130Y-40383D01*
X90256Y-42425D01*
X89820Y-44467D01*
X90038Y-46217D01*
X90912Y-48259D01*
X92222Y-49717D01*
X93968Y-50300D01*
X95278Y-50008D01*
X96807Y-48842D01*
X97680Y-47676D01*
G01X107975Y-42425D02*
X114962D01*
X114307Y-40383D01*
X113215Y-39217D01*
X111687Y-38634D01*
X110158Y-38925D01*
X108848Y-39800D01*
X107975Y-41842D01*
X107538Y-43592D01*
Y-45342D01*
X107975Y-47092D01*
X109067Y-48842D01*
X110377Y-50008D01*
X111905Y-50300D01*
X113433Y-49717D01*
X114962Y-47967D01*
G01X125693Y-50300D02*
Y-38634D01*
G01Y-40967D02*
X126785Y-39800D01*
X127877Y-38925D01*
X129405Y-38634D01*
X130496Y-38925D01*
X131807Y-39800D01*
G01X142320Y-50300D02*
Y-32800D01*
G01Y-41550D02*
X143412Y-39800D01*
X144722Y-38925D01*
X146032Y-38634D01*
X147996Y-39217D01*
X149307Y-40383D01*
X150180Y-42425D01*
Y-44758D01*
X149743Y-47092D01*
X148870Y-48842D01*
X147342Y-50008D01*
X146032Y-50300D01*
X144722Y-50008D01*
X143412Y-49134D01*
X142320Y-47676D01*
G01X160475Y-42425D02*
X167462D01*
X166807Y-40383D01*
X165715Y-39217D01*
X164187Y-38634D01*
X162658Y-38925D01*
X161348Y-39800D01*
X160475Y-41842D01*
X160038Y-43592D01*
Y-45342D01*
X160475Y-47092D01*
X161567Y-48842D01*
X162877Y-50008D01*
X164405Y-50300D01*
X165933Y-49717D01*
X167462Y-47967D01*
G01X178193Y-50300D02*
Y-38634D01*
G01Y-40967D02*
X179285Y-39800D01*
X180377Y-38925D01*
X181905Y-38634D01*
X182996Y-38925D01*
X184307Y-39800D01*
G01X216250Y-38634D02*
Y-50300D01*
G01Y-33967D02*
X215813Y-33675D01*
Y-33092D01*
X216250Y-32800D01*
X216687Y-33092D01*
Y-33675D01*
X216250Y-33967D01*
G01X230475Y-48259D02*
X231567Y-49425D01*
X233095Y-50300D01*
X234405D01*
X235715Y-49717D01*
X236588Y-48842D01*
X237025Y-47676D01*
X236807Y-45925D01*
X235933Y-45050D01*
X232003Y-43300D01*
X231130Y-41258D01*
X231567Y-39800D01*
X232440Y-38925D01*
X233750Y-38634D01*
X235060Y-38925D01*
X236370Y-39800D01*
G01X265256Y-54675D02*
X266785Y-55842D01*
X268095Y-56133D01*
X269842Y-55550D01*
X271152Y-54092D01*
X271807Y-51466D01*
Y-38634D01*
G01Y-33967D02*
X271370Y-33675D01*
Y-33092D01*
X271807Y-32800D01*
X272243Y-33092D01*
Y-33675D01*
X271807Y-33967D01*
G01X282538Y-38634D02*
Y-46800D01*
X283412Y-48842D01*
X284722Y-50008D01*
X286250Y-50300D01*
X287778Y-50008D01*
X289088Y-48842D01*
X289962Y-46800D01*
G01Y-50300D02*
Y-38634D01*
G01X300475Y-48259D02*
X301567Y-49425D01*
X303095Y-50300D01*
X304405D01*
X305715Y-49717D01*
X306588Y-48842D01*
X307025Y-47676D01*
X306807Y-45925D01*
X305933Y-45050D01*
X302003Y-43300D01*
X301130Y-41258D01*
X301567Y-39800D01*
X302440Y-38925D01*
X303750Y-38634D01*
X305060Y-38925D01*
X306370Y-39800D01*
G01X321250Y-32800D02*
Y-50300D01*
G01X318193Y-38634D02*
X324307D01*
G01X354940Y-50300D02*
Y-35425D01*
X355377Y-33967D01*
X356250Y-33092D01*
X357560Y-32800D01*
X358870Y-33383D01*
X359525Y-34842D01*
G01X356905Y-39800D02*
X352538D01*
G01X373750Y-50300D02*
X372440Y-50008D01*
X371130Y-48842D01*
X370256Y-46800D01*
X369820Y-44467D01*
X370256Y-42133D01*
X371130Y-40092D01*
X372440Y-38925D01*
X373750Y-38634D01*
X375060Y-38925D01*
X376370Y-40092D01*
X377243Y-42133D01*
X377462Y-44467D01*
X377243Y-46800D01*
X376370Y-48842D01*
X375060Y-50008D01*
X373750Y-50300D01*
G01X388193D02*
Y-38634D01*
G01Y-40967D02*
X389285Y-39800D01*
X390377Y-38925D01*
X391905Y-38634D01*
X392996Y-38925D01*
X394307Y-39800D01*
G01X421665Y-55550D02*
X422975Y-56133D01*
X424722Y-55550D01*
X425813Y-54384D01*
X426687Y-52925D01*
X427996Y-48259D01*
X430835Y-38634D01*
G01X423848D02*
X427996Y-48259D01*
G01X443750Y-50300D02*
X442440Y-50008D01*
X441130Y-48842D01*
X440256Y-46800D01*
X439820Y-44467D01*
X440256Y-42133D01*
X441130Y-40092D01*
X442440Y-38925D01*
X443750Y-38634D01*
X445060Y-38925D01*
X446370Y-40092D01*
X447243Y-42133D01*
X447462Y-44467D01*
X447243Y-46800D01*
X446370Y-48842D01*
X445060Y-50008D01*
X443750Y-50300D01*
G01X457538Y-38634D02*
Y-46800D01*
X458412Y-48842D01*
X459722Y-50008D01*
X461250Y-50300D01*
X462778Y-50008D01*
X464088Y-48842D01*
X464962Y-46800D01*
G01Y-50300D02*
Y-38634D01*
G01X475693Y-50300D02*
Y-38634D01*
G01Y-40967D02*
X476785Y-39800D01*
X477877Y-38925D01*
X479405Y-38634D01*
X480496Y-38925D01*
X481807Y-39800D01*
G01X510693Y-50300D02*
Y-38634D01*
G01Y-40967D02*
X511785Y-39800D01*
X512877Y-38925D01*
X514405Y-38634D01*
X515496Y-38925D01*
X516807Y-39800D01*
G01X527975Y-42425D02*
X534962D01*
X534307Y-40383D01*
X533215Y-39217D01*
X531687Y-38634D01*
X530158Y-38925D01*
X528848Y-39800D01*
X527975Y-41842D01*
X527538Y-43592D01*
Y-45342D01*
X527975Y-47092D01*
X529067Y-48842D01*
X530377Y-50008D01*
X531905Y-50300D01*
X533433Y-49717D01*
X534962Y-47967D01*
G01X547440Y-50300D02*
Y-35425D01*
X547877Y-33967D01*
X548750Y-33092D01*
X550060Y-32800D01*
X551370Y-33383D01*
X552025Y-34842D01*
G01X549405Y-39800D02*
X545038D01*
G01X562975Y-42425D02*
X569962D01*
X569307Y-40383D01*
X568215Y-39217D01*
X566687Y-38634D01*
X565158Y-38925D01*
X563848Y-39800D01*
X562975Y-41842D01*
X562538Y-43592D01*
Y-45342D01*
X562975Y-47092D01*
X564067Y-48842D01*
X565377Y-50008D01*
X566905Y-50300D01*
X568433Y-49717D01*
X569962Y-47967D01*
G01X580693Y-50300D02*
Y-38634D01*
G01Y-40967D02*
X581785Y-39800D01*
X582877Y-38925D01*
X584405Y-38634D01*
X585496Y-38925D01*
X586807Y-39800D01*
G01X597975Y-42425D02*
X604962D01*
X604307Y-40383D01*
X603215Y-39217D01*
X601687Y-38634D01*
X600158Y-38925D01*
X598848Y-39800D01*
X597975Y-41842D01*
X597538Y-43592D01*
Y-45342D01*
X597975Y-47092D01*
X599067Y-48842D01*
X600377Y-50008D01*
X601905Y-50300D01*
X603433Y-49717D01*
X604962Y-47967D01*
G01X615038Y-50300D02*
Y-38634D01*
G01Y-41550D02*
X615912Y-40092D01*
X617222Y-38925D01*
X618968Y-38634D01*
X620496Y-38925D01*
X621807Y-40092D01*
X622462Y-42133D01*
Y-50300D01*
G01X639743Y-40092D02*
X638215Y-38925D01*
X636905Y-38634D01*
X635158Y-39217D01*
X633848Y-40383D01*
X632975Y-42425D01*
X632756Y-44467D01*
X632975Y-46509D01*
X633848Y-48259D01*
X635158Y-49717D01*
X636905Y-50300D01*
X638433Y-49717D01*
X639743Y-48550D01*
G01X650475Y-42425D02*
X657462D01*
X656807Y-40383D01*
X655715Y-39217D01*
X654187Y-38634D01*
X652658Y-38925D01*
X651348Y-39800D01*
X650475Y-41842D01*
X650038Y-43592D01*
Y-45342D01*
X650475Y-47092D01*
X651567Y-48842D01*
X652877Y-50008D01*
X654405Y-50300D01*
X655933Y-49717D01*
X657462Y-47967D01*
G01X688750Y-32800D02*
Y-50300D01*
G01X685693Y-38634D02*
X691807D01*
G01X706250Y-50300D02*
X704940Y-50008D01*
X703630Y-48842D01*
X702756Y-46800D01*
X702320Y-44467D01*
X702756Y-42133D01*
X703630Y-40092D01*
X704940Y-38925D01*
X706250Y-38634D01*
X707560Y-38925D01*
X708870Y-40092D01*
X709743Y-42133D01*
X709962Y-44467D01*
X709743Y-46800D01*
X708870Y-48842D01*
X707560Y-50008D01*
X706250Y-50300D01*
G01X739940D02*
Y-35425D01*
X740377Y-33967D01*
X741250Y-33092D01*
X742560Y-32800D01*
X743870Y-33383D01*
X744525Y-34842D01*
G01X741905Y-39800D02*
X737538D01*
G01X758750Y-38634D02*
Y-50300D01*
G01Y-33967D02*
X758313Y-33675D01*
Y-33092D01*
X758750Y-32800D01*
X759187Y-33092D01*
Y-33675D01*
X758750Y-33967D01*
G01X772538Y-50300D02*
Y-38634D01*
G01Y-41550D02*
X773412Y-40092D01*
X774722Y-38925D01*
X776468Y-38634D01*
X777996Y-38925D01*
X779307Y-40092D01*
X779962Y-42133D01*
Y-50300D01*
G01X797680Y-32800D02*
Y-50300D01*
G01Y-47676D02*
X796807Y-49134D01*
X795496Y-50008D01*
X793968Y-50300D01*
X792222Y-49717D01*
X790912Y-48259D01*
X790038Y-46509D01*
X789820Y-44467D01*
X790038Y-42425D01*
X790912Y-40675D01*
X792222Y-39217D01*
X793968Y-38634D01*
X795496Y-38925D01*
X796588Y-39509D01*
X797680Y-40675D01*
G01X828750Y-32800D02*
Y-50300D01*
G01X825693Y-38634D02*
X831807D01*
G01X842538Y-50300D02*
Y-32800D01*
G01Y-41258D02*
X843630Y-39800D01*
X844722Y-38925D01*
X846468Y-38634D01*
X847778Y-38925D01*
X849307Y-40092D01*
X849962Y-41842D01*
Y-50300D01*
G01X860475Y-42425D02*
X867462D01*
X866807Y-40383D01*
X865715Y-39217D01*
X864187Y-38634D01*
X862658Y-38925D01*
X861348Y-39800D01*
X860475Y-41842D01*
X860038Y-43592D01*
Y-45342D01*
X860475Y-47092D01*
X861567Y-48842D01*
X862877Y-50008D01*
X864405Y-50300D01*
X865933Y-49717D01*
X867462Y-47967D01*
G01X893947Y-50300D02*
Y-32800D01*
X898313D01*
X900060Y-33675D01*
X901370Y-34842D01*
X902462Y-36591D01*
X903335Y-38634D01*
X903553Y-41550D01*
X903335Y-44467D01*
X902462Y-46509D01*
X901370Y-48259D01*
X900060Y-49425D01*
X898313Y-50300D01*
X893947D01*
G01X911883D02*
Y-32800D01*
X917123D01*
X918870Y-33675D01*
X920180Y-35717D01*
X920617Y-38050D01*
X920180Y-40383D01*
X919088Y-42133D01*
X917123Y-43009D01*
X911883D01*
G01X951250Y-38634D02*
Y-50300D01*
G01Y-33967D02*
X950813Y-33675D01*
Y-33092D01*
X951250Y-32800D01*
X951687Y-33092D01*
Y-33675D01*
X951250Y-33967D01*
G01X962200Y-50300D02*
Y-38634D01*
G01Y-41842D02*
X962855Y-40383D01*
X963947Y-39217D01*
X965475Y-38634D01*
X967003Y-39217D01*
X968095Y-40383D01*
X968750Y-41842D01*
Y-50300D01*
G01Y-41842D02*
X969405Y-40383D01*
X970496Y-39217D01*
X972025Y-38634D01*
X973553Y-39217D01*
X974645Y-40383D01*
X975300Y-42133D01*
Y-50300D01*
G01X982320Y-56133D02*
Y-38634D01*
G01Y-41258D02*
X983412Y-39800D01*
X984503Y-38925D01*
X986250Y-38634D01*
X987778Y-38925D01*
X989307Y-40383D01*
X989962Y-42425D01*
X990180Y-44467D01*
X989962Y-46509D01*
X989307Y-48550D01*
X987996Y-49717D01*
X986250Y-50300D01*
X984722Y-50008D01*
X983193Y-49134D01*
X982320Y-47967D01*
G01X1000475Y-42425D02*
X1007462D01*
X1006807Y-40383D01*
X1005715Y-39217D01*
X1004187Y-38634D01*
X1002658Y-38925D01*
X1001348Y-39800D01*
X1000475Y-41842D01*
X1000038Y-43592D01*
Y-45342D01*
X1000475Y-47092D01*
X1001567Y-48842D01*
X1002877Y-50008D01*
X1004405Y-50300D01*
X1005933Y-49717D01*
X1007462Y-47967D01*
G01X1025180Y-32800D02*
Y-50300D01*
G01Y-47676D02*
X1024307Y-49134D01*
X1022996Y-50008D01*
X1021468Y-50300D01*
X1019722Y-49717D01*
X1018412Y-48259D01*
X1017538Y-46509D01*
X1017320Y-44467D01*
X1017538Y-42425D01*
X1018412Y-40675D01*
X1019722Y-39217D01*
X1021468Y-38634D01*
X1022996Y-38925D01*
X1024088Y-39509D01*
X1025180Y-40675D01*
G01X1042680Y-50300D02*
Y-38634D01*
G01Y-40675D02*
X1041807Y-39509D01*
X1040496Y-38925D01*
X1038968Y-38634D01*
X1037440Y-39217D01*
X1036130Y-40383D01*
X1035256Y-42133D01*
X1034820Y-44467D01*
X1035256Y-46800D01*
X1036130Y-48550D01*
X1037440Y-49717D01*
X1038968Y-50300D01*
X1040496Y-50008D01*
X1041807Y-49134D01*
X1042680Y-47967D01*
G01X1052538Y-50300D02*
Y-38634D01*
G01Y-41550D02*
X1053412Y-40092D01*
X1054722Y-38925D01*
X1056468Y-38634D01*
X1057996Y-38925D01*
X1059307Y-40092D01*
X1059962Y-42133D01*
Y-50300D01*
G01X1077243Y-40092D02*
X1075715Y-38925D01*
X1074405Y-38634D01*
X1072658Y-39217D01*
X1071348Y-40383D01*
X1070475Y-42425D01*
X1070256Y-44467D01*
X1070475Y-46509D01*
X1071348Y-48259D01*
X1072658Y-49717D01*
X1074405Y-50300D01*
X1075933Y-49717D01*
X1077243Y-48550D01*
G01X1087975Y-42425D02*
X1094962D01*
X1094307Y-40383D01*
X1093215Y-39217D01*
X1091687Y-38634D01*
X1090158Y-38925D01*
X1088848Y-39800D01*
X1087975Y-41842D01*
X1087538Y-43592D01*
Y-45342D01*
X1087975Y-47092D01*
X1089067Y-48842D01*
X1090377Y-50008D01*
X1091905Y-50300D01*
X1093433Y-49717D01*
X1094962Y-47967D01*
G01X1126250Y-32800D02*
Y-50300D01*
G01X1123193Y-38634D02*
X1129307D01*
G01X1140693Y-50300D02*
Y-38634D01*
G01Y-40967D02*
X1141785Y-39800D01*
X1142877Y-38925D01*
X1144405Y-38634D01*
X1145496Y-38925D01*
X1146807Y-39800D01*
G01X1165180Y-50300D02*
Y-38634D01*
G01Y-40675D02*
X1164307Y-39509D01*
X1162996Y-38925D01*
X1161468Y-38634D01*
X1159940Y-39217D01*
X1158630Y-40383D01*
X1157756Y-42133D01*
X1157320Y-44467D01*
X1157756Y-46800D01*
X1158630Y-48550D01*
X1159940Y-49717D01*
X1161468Y-50300D01*
X1162996Y-50008D01*
X1164307Y-49134D01*
X1165180Y-47967D01*
G01X1182243Y-40092D02*
X1180715Y-38925D01*
X1179405Y-38634D01*
X1177658Y-39217D01*
X1176348Y-40383D01*
X1175475Y-42425D01*
X1175256Y-44467D01*
X1175475Y-46509D01*
X1176348Y-48259D01*
X1177658Y-49717D01*
X1179405Y-50300D01*
X1180933Y-49717D01*
X1182243Y-48550D01*
G01X1192975Y-42425D02*
X1199962D01*
X1199307Y-40383D01*
X1198215Y-39217D01*
X1196687Y-38634D01*
X1195158Y-38925D01*
X1193848Y-39800D01*
X1192975Y-41842D01*
X1192538Y-43592D01*
Y-45342D01*
X1192975Y-47092D01*
X1194067Y-48842D01*
X1195377Y-50008D01*
X1196905Y-50300D01*
X1198433Y-49717D01*
X1199962Y-47967D01*
G01X1210475Y-48259D02*
X1211567Y-49425D01*
X1213095Y-50300D01*
X1214405D01*
X1215715Y-49717D01*
X1216588Y-48842D01*
X1217025Y-47676D01*
X1216807Y-45925D01*
X1215933Y-45050D01*
X1212003Y-43300D01*
X1211130Y-41258D01*
X1211567Y-39800D01*
X1212440Y-38925D01*
X1213750Y-38634D01*
X1215060Y-38925D01*
X1216370Y-39800D01*
G01X1248750Y-38634D02*
Y-50300D01*
G01Y-33967D02*
X1248313Y-33675D01*
Y-33092D01*
X1248750Y-32800D01*
X1249187Y-33092D01*
Y-33675D01*
X1248750Y-33967D01*
G01X1262538Y-50300D02*
Y-38634D01*
G01Y-41550D02*
X1263412Y-40092D01*
X1264722Y-38925D01*
X1266468Y-38634D01*
X1267996Y-38925D01*
X1269307Y-40092D01*
X1269962Y-42133D01*
Y-50300D01*
G01X1301250D02*
Y-32800D01*
G01X1322680Y-50300D02*
Y-38634D01*
G01Y-40675D02*
X1321807Y-39509D01*
X1320496Y-38925D01*
X1318968Y-38634D01*
X1317440Y-39217D01*
X1316130Y-40383D01*
X1315256Y-42133D01*
X1314820Y-44467D01*
X1315256Y-46800D01*
X1316130Y-48550D01*
X1317440Y-49717D01*
X1318968Y-50300D01*
X1320496Y-50008D01*
X1321807Y-49134D01*
X1322680Y-47967D01*
G01X1331665Y-55550D02*
X1332975Y-56133D01*
X1334722Y-55550D01*
X1335813Y-54384D01*
X1336687Y-52925D01*
X1337996Y-48259D01*
X1340835Y-38634D01*
G01X1333848D02*
X1337996Y-48259D01*
G01X1350475Y-42425D02*
X1357462D01*
X1356807Y-40383D01*
X1355715Y-39217D01*
X1354187Y-38634D01*
X1352658Y-38925D01*
X1351348Y-39800D01*
X1350475Y-41842D01*
X1350038Y-43592D01*
Y-45342D01*
X1350475Y-47092D01*
X1351567Y-48842D01*
X1352877Y-50008D01*
X1354405Y-50300D01*
X1355933Y-49717D01*
X1357462Y-47967D01*
G01X1368193Y-50300D02*
Y-38634D01*
G01Y-40967D02*
X1369285Y-39800D01*
X1370377Y-38925D01*
X1371905Y-38634D01*
X1372996Y-38925D01*
X1374307Y-39800D01*
G01X1401883Y-32800D02*
Y-50300D01*
X1410617D01*
G01X1423750D02*
X1425278Y-50008D01*
X1427025Y-49134D01*
X1428117Y-47676D01*
X1428553Y-45633D01*
X1428117Y-43592D01*
X1426807Y-41842D01*
X1424842Y-40967D01*
X1422658D01*
X1421348Y-40383D01*
X1420256Y-38925D01*
X1419820Y-36884D01*
X1420475Y-34842D01*
X1422003Y-33383D01*
X1423750Y-32800D01*
X1425496Y-33383D01*
X1427025Y-34842D01*
X1427680Y-36884D01*
X1427243Y-38925D01*
X1426152Y-40383D01*
X1424842Y-40967D01*
X1422658D01*
X1420693Y-41842D01*
X1419383Y-43592D01*
X1418947Y-45633D01*
X1419383Y-47676D01*
X1420475Y-49134D01*
X1422222Y-50008D01*
X1423750Y-50300D01*
G01X1441250Y-50883D02*
X1440813Y-50592D01*
Y-50008D01*
X1441250Y-49717D01*
X1441687Y-50008D01*
Y-50592D01*
X1441250Y-50883D01*
G01X999127Y722030D02*
X1004367D01*
G01X1001747D02*
Y704530D01*
G01X999127D02*
X1004367D01*
G01X1013570D02*
Y722030D01*
X1019247Y707447D01*
X1024924Y722030D01*
Y704530D01*
G01X1032380D02*
Y722030D01*
X1037620D01*
X1039367Y721155D01*
X1040677Y719113D01*
X1041114Y716780D01*
X1040677Y714447D01*
X1039585Y712697D01*
X1037620Y711821D01*
X1032380D01*
G01X1053155Y698697D02*
X1050972Y701613D01*
X1049880Y704530D01*
Y716196D01*
X1050972Y719113D01*
X1053155Y722030D01*
G01X1071747Y704530D02*
X1070000Y704822D01*
X1068472Y705988D01*
X1067162Y707738D01*
X1066288Y709780D01*
X1065852Y712113D01*
Y714447D01*
X1066288Y716780D01*
X1067162Y718822D01*
X1068472Y720571D01*
X1070000Y721738D01*
X1071747Y722030D01*
X1073493Y721738D01*
X1075022Y720571D01*
X1076332Y718822D01*
X1077206Y716780D01*
X1077642Y714447D01*
Y712113D01*
X1077206Y709780D01*
X1076332Y707738D01*
X1075022Y705988D01*
X1073493Y704822D01*
X1071747Y704530D01*
G01X1085535D02*
Y722030D01*
G01Y713572D02*
X1086627Y715030D01*
X1087719Y715905D01*
X1089465Y716196D01*
X1090775Y715905D01*
X1092304Y714738D01*
X1092959Y712988D01*
Y704530D01*
G01X1100197D02*
Y716196D01*
G01Y712988D02*
X1100852Y714447D01*
X1101944Y715613D01*
X1103472Y716196D01*
X1105000Y715613D01*
X1106092Y714447D01*
X1106747Y712988D01*
Y704530D01*
G01Y712988D02*
X1107402Y714447D01*
X1108493Y715613D01*
X1110022Y716196D01*
X1111550Y715613D01*
X1112642Y714447D01*
X1113297Y712697D01*
Y704530D01*
G01X1125339Y698697D02*
X1127522Y701613D01*
X1128614Y704530D01*
Y716196D01*
X1127522Y719113D01*
X1125339Y722030D01*
G01X977244Y739180D02*
Y756680D01*
X981610D01*
X983357Y755805D01*
X984667Y754638D01*
X985759Y752889D01*
X986632Y750846D01*
X986850Y747930D01*
X986632Y745013D01*
X985759Y742971D01*
X984667Y741221D01*
X983357Y740055D01*
X981610Y739180D01*
X977244D01*
G01X995180D02*
Y756680D01*
X1000420D01*
X1002167Y755805D01*
X1003477Y753763D01*
X1003914Y751430D01*
X1003477Y749097D01*
X1002385Y747347D01*
X1000420Y746471D01*
X995180D01*
G01X1031927Y756680D02*
X1037167D01*
G01X1034547D02*
Y739180D01*
G01X1031927D02*
X1037167D01*
G01X1046370D02*
Y756680D01*
X1052047Y742097D01*
X1057724Y756680D01*
Y739180D01*
G01X1065180D02*
Y756680D01*
X1070420D01*
X1072167Y755805D01*
X1073477Y753763D01*
X1073914Y751430D01*
X1073477Y749097D01*
X1072385Y747347D01*
X1070420Y746471D01*
X1065180D01*
G01X1091414Y739180D02*
X1082680D01*
Y756680D01*
X1091414D01*
G01X1087920Y748222D02*
X1082680D01*
G01X1099744Y739180D02*
Y756680D01*
X1104110D01*
X1105857Y755805D01*
X1107167Y754638D01*
X1108259Y752889D01*
X1109132Y750846D01*
X1109350Y747930D01*
X1109132Y745013D01*
X1108259Y742971D01*
X1107167Y741221D01*
X1105857Y740055D01*
X1104110Y739180D01*
X1099744D01*
G01X1116588D02*
X1122047Y756680D01*
X1127506Y739180D01*
G01X1125540Y745305D02*
X1118553D01*
G01X1134525Y739180D02*
Y756680D01*
X1144569Y739180D01*
Y756680D01*
G01X1161850Y755221D02*
X1160540Y756097D01*
X1159012Y756680D01*
X1157265D01*
X1155300Y755805D01*
X1153772Y754347D01*
X1152680Y752596D01*
X1151807Y749680D01*
X1151588Y747055D01*
X1152025Y744430D01*
X1152680Y742680D01*
X1153990Y740930D01*
X1155519Y739763D01*
X1157047Y739180D01*
X1158575D01*
X1160104Y739763D01*
X1161414Y740638D01*
X1162506Y741804D01*
G01X1178914Y739180D02*
X1170180D01*
Y756680D01*
X1178914D01*
G01X1175420Y748222D02*
X1170180D01*
G01X1209547Y756680D02*
Y739180D01*
G01X1204525Y756680D02*
X1214569D01*
G01X1221588Y739180D02*
X1227047Y756680D01*
X1232506Y739180D01*
G01X1230540Y745305D02*
X1223553D01*
G01X1246293Y748513D02*
X1247167Y749388D01*
X1247822Y750846D01*
X1248259Y752889D01*
X1247822Y754638D01*
X1246949Y755805D01*
X1245420Y756680D01*
X1239525D01*
Y739180D01*
X1246730D01*
X1248259Y740346D01*
X1249132Y742097D01*
X1249569Y744138D01*
X1249132Y746180D01*
X1247822Y747930D01*
X1246293Y748513D01*
X1239525D01*
G01X1257680Y756680D02*
Y739180D01*
X1266414D01*
G01X1283914D02*
X1275180D01*
Y756680D01*
X1283914D01*
G01X1280420Y748222D02*
X1275180D01*
G01X1297047Y738597D02*
X1296610Y738888D01*
Y739472D01*
X1297047Y739763D01*
X1297484Y739472D01*
Y738888D01*
X1297047Y738597D01*
G01Y746471D02*
X1296610Y746763D01*
Y747347D01*
X1297047Y747638D01*
X1297484Y747347D01*
Y746763D01*
X1297047Y746471D01*
G01X1327680Y756680D02*
Y739180D01*
X1336414D01*
G01X1349547D02*
X1351075Y739472D01*
X1352822Y740346D01*
X1353914Y741804D01*
X1354350Y743847D01*
X1353914Y745888D01*
X1352604Y747638D01*
X1350639Y748513D01*
X1348455D01*
X1347145Y749097D01*
X1346053Y750555D01*
X1345617Y752596D01*
X1346272Y754638D01*
X1347800Y756097D01*
X1349547Y756680D01*
X1351293Y756097D01*
X1352822Y754638D01*
X1353477Y752596D01*
X1353040Y750555D01*
X1351949Y749097D01*
X1350639Y748513D01*
X1348455D01*
X1346490Y747638D01*
X1345180Y745888D01*
X1344744Y743847D01*
X1345180Y741804D01*
X1346272Y740346D01*
X1348019Y739472D01*
X1349547Y739180D01*
G01X1027997Y635230D02*
Y652730D01*
X1025377Y649230D01*
G01Y635230D02*
X1030617D01*
G01X1045497Y652730D02*
X1043750Y652147D01*
X1042440Y650688D01*
X1041567Y648939D01*
X1040912Y646605D01*
X1040694Y643980D01*
X1040912Y641355D01*
X1041567Y639021D01*
X1042440Y637271D01*
X1043750Y635813D01*
X1045497Y635230D01*
X1047243Y635813D01*
X1048554Y637271D01*
X1049427Y639021D01*
X1050082Y641355D01*
X1050300Y643980D01*
X1050082Y646605D01*
X1049427Y648939D01*
X1048554Y650688D01*
X1047243Y652147D01*
X1045497Y652730D01*
G01X1062997D02*
X1061250Y652147D01*
X1059940Y650688D01*
X1059067Y648939D01*
X1058412Y646605D01*
X1058194Y643980D01*
X1058412Y641355D01*
X1059067Y639021D01*
X1059940Y637271D01*
X1061250Y635813D01*
X1062997Y635230D01*
X1064743Y635813D01*
X1066054Y637271D01*
X1066927Y639021D01*
X1067582Y641355D01*
X1067800Y643980D01*
X1067582Y646605D01*
X1066927Y648939D01*
X1066054Y650688D01*
X1064743Y652147D01*
X1062997Y652730D01*
G01X1080497Y634647D02*
X1080060Y634938D01*
Y635522D01*
X1080497Y635813D01*
X1080934Y635522D01*
Y634938D01*
X1080497Y634647D01*
G01X1097997Y652730D02*
X1096250Y652147D01*
X1094940Y650688D01*
X1094067Y648939D01*
X1093412Y646605D01*
X1093194Y643980D01*
X1093412Y641355D01*
X1094067Y639021D01*
X1094940Y637271D01*
X1096250Y635813D01*
X1097997Y635230D01*
X1099743Y635813D01*
X1101054Y637271D01*
X1101927Y639021D01*
X1102582Y641355D01*
X1102800Y643980D01*
X1102582Y646605D01*
X1101927Y648939D01*
X1101054Y650688D01*
X1099743Y652147D01*
X1097997Y652730D01*
G01X1036747Y669880D02*
X1038275Y670172D01*
X1040022Y671046D01*
X1041114Y672504D01*
X1041550Y674547D01*
X1041114Y676588D01*
X1039804Y678338D01*
X1037839Y679213D01*
X1035655D01*
X1034345Y679797D01*
X1033253Y681255D01*
X1032817Y683296D01*
X1033472Y685338D01*
X1035000Y686797D01*
X1036747Y687380D01*
X1038493Y686797D01*
X1040022Y685338D01*
X1040677Y683296D01*
X1040240Y681255D01*
X1039149Y679797D01*
X1037839Y679213D01*
X1035655D01*
X1033690Y678338D01*
X1032380Y676588D01*
X1031944Y674547D01*
X1032380Y672504D01*
X1033472Y671046D01*
X1035219Y670172D01*
X1036747Y669880D01*
G01X1049444Y672504D02*
X1050753Y671046D01*
X1052282Y670172D01*
X1054247Y669880D01*
X1056212Y670463D01*
X1057740Y671630D01*
X1058832Y673671D01*
X1059050Y676005D01*
X1058614Y678338D01*
X1057522Y679797D01*
X1055993Y680963D01*
X1054465Y681255D01*
X1052937Y680963D01*
X1050972Y679797D01*
X1051627Y687380D01*
X1057522D01*
G01X1071747Y669297D02*
X1071310Y669588D01*
Y670172D01*
X1071747Y670463D01*
X1072184Y670172D01*
Y669588D01*
X1071747Y669297D01*
G01X1089247Y687380D02*
X1087500Y686797D01*
X1086190Y685338D01*
X1085317Y683589D01*
X1084662Y681255D01*
X1084444Y678630D01*
X1084662Y676005D01*
X1085317Y673671D01*
X1086190Y671921D01*
X1087500Y670463D01*
X1089247Y669880D01*
X1090993Y670463D01*
X1092304Y671921D01*
X1093177Y673671D01*
X1093832Y676005D01*
X1094050Y678630D01*
X1093832Y681255D01*
X1093177Y683589D01*
X1092304Y685338D01*
X1090993Y686797D01*
X1089247Y687380D01*
G01X1223117Y635230D02*
Y652730D01*
X1215038Y640188D01*
X1225956D01*
G01X1237997Y634647D02*
X1237560Y634938D01*
Y635522D01*
X1237997Y635813D01*
X1238434Y635522D01*
Y634938D01*
X1237997Y634647D01*
G01X1251785Y637271D02*
X1253314Y635813D01*
X1255060Y635230D01*
X1256807Y635813D01*
X1258335Y637563D01*
X1259427Y640188D01*
X1259864Y642813D01*
Y646021D01*
X1259427Y648646D01*
X1258335Y650980D01*
X1257025Y652147D01*
X1255497Y652730D01*
X1253750Y652147D01*
X1252440Y650980D01*
X1251567Y649230D01*
X1251130Y646896D01*
X1251567Y644855D01*
X1252659Y642813D01*
X1253969Y641646D01*
X1255497Y641355D01*
X1257243Y641938D01*
X1258554Y643397D01*
X1259864Y646021D01*
G01X1269067Y634647D02*
X1276927Y652730D01*
G01X1290497Y635230D02*
Y652730D01*
X1287877Y649230D01*
G01Y635230D02*
X1293117D01*
G01X1307997D02*
Y652730D01*
X1305377Y649230D01*
G01Y635230D02*
X1310617D01*
G01X1325497Y634647D02*
X1325060Y634938D01*
Y635522D01*
X1325497Y635813D01*
X1325934Y635522D01*
Y634938D01*
X1325497Y634647D01*
G01X1342997Y635230D02*
Y652730D01*
X1340377Y649230D01*
G01Y635230D02*
X1345617D01*
G01X1187697Y722030D02*
X1190753Y704530D01*
X1194247Y722030D01*
X1197740Y704530D01*
X1200797Y722030D01*
G01X1209127D02*
X1214367D01*
G01X1211747D02*
Y704530D01*
G01X1209127D02*
X1214367D01*
G01X1224444D02*
Y722030D01*
X1228810D01*
X1230557Y721155D01*
X1231867Y719988D01*
X1232959Y718239D01*
X1233832Y716196D01*
X1234050Y713280D01*
X1233832Y710363D01*
X1232959Y708321D01*
X1231867Y706571D01*
X1230557Y705405D01*
X1228810Y704530D01*
X1224444D01*
G01X1246747Y722030D02*
Y704530D01*
G01X1241725Y722030D02*
X1251769D01*
G01X1259662Y704530D02*
Y722030D01*
G01X1268832D02*
Y704530D01*
G01Y713280D02*
X1259662D01*
G01X1280655Y698697D02*
X1278472Y701613D01*
X1277380Y704530D01*
Y716196D01*
X1278472Y719113D01*
X1280655Y722030D01*
G01X1292697Y704530D02*
Y716196D01*
G01Y712988D02*
X1293352Y714447D01*
X1294444Y715613D01*
X1295972Y716196D01*
X1297500Y715613D01*
X1298592Y714447D01*
X1299247Y712988D01*
Y704530D01*
G01Y712988D02*
X1299902Y714447D01*
X1300993Y715613D01*
X1302522Y716196D01*
X1304050Y715613D01*
X1305142Y714447D01*
X1305797Y712697D01*
Y704530D01*
G01X1316747Y716196D02*
Y704530D01*
G01Y720863D02*
X1316310Y721155D01*
Y721738D01*
X1316747Y722030D01*
X1317184Y721738D01*
Y721155D01*
X1316747Y720863D01*
G01X1334247Y704530D02*
Y722030D01*
G01X1348472Y706571D02*
X1349564Y705405D01*
X1351092Y704530D01*
X1352402D01*
X1353712Y705113D01*
X1354585Y705988D01*
X1355022Y707154D01*
X1354804Y708905D01*
X1353930Y709780D01*
X1350000Y711530D01*
X1349127Y713572D01*
X1349564Y715030D01*
X1350437Y715905D01*
X1351747Y716196D01*
X1353057Y715905D01*
X1354367Y715030D01*
G01X1370339Y698697D02*
X1372522Y701613D01*
X1373614Y704530D01*
Y716196D01*
X1372522Y719113D01*
X1370339Y722030D01*
G01X1215694Y672504D02*
X1217003Y671046D01*
X1218532Y670172D01*
X1220497Y669880D01*
X1222462Y670463D01*
X1223990Y671630D01*
X1225082Y673671D01*
X1225300Y676005D01*
X1224864Y678338D01*
X1223772Y679797D01*
X1222243Y680963D01*
X1220715Y681255D01*
X1219187Y680963D01*
X1217222Y679797D01*
X1217877Y687380D01*
X1223772D01*
G01X1237997Y669297D02*
X1237560Y669588D01*
Y670172D01*
X1237997Y670463D01*
X1238434Y670172D01*
Y669588D01*
X1237997Y669297D01*
G01X1255060Y669880D02*
X1255497Y673671D01*
X1256152Y676880D01*
X1257025Y679797D01*
X1258117Y683005D01*
X1259864Y687380D01*
X1251130D01*
G01X1268194Y672504D02*
X1269503Y671046D01*
X1271032Y670172D01*
X1272997Y669880D01*
X1274962Y670463D01*
X1276490Y671630D01*
X1277582Y673671D01*
X1277800Y676005D01*
X1277364Y678338D01*
X1276272Y679797D01*
X1274743Y680963D01*
X1273215Y681255D01*
X1271687Y680963D01*
X1269722Y679797D01*
X1270377Y687380D01*
X1276272D01*
G01X1286567Y669297D02*
X1294427Y687380D01*
G01X1303849Y677171D02*
X1305377Y679213D01*
X1306687Y680380D01*
X1308434Y680963D01*
X1309962Y680380D01*
X1311054Y679213D01*
X1311927Y677463D01*
X1312145Y675422D01*
X1311927Y673671D01*
X1311054Y671921D01*
X1309743Y670463D01*
X1308215Y669880D01*
X1306469Y670463D01*
X1304940Y672213D01*
X1304067Y674838D01*
X1303849Y677755D01*
X1304285Y681546D01*
X1304940Y683589D01*
X1306032Y685630D01*
X1307560Y687088D01*
X1309089Y687380D01*
X1310617Y686797D01*
X1311709Y685338D01*
G01X1325497Y669297D02*
X1325060Y669588D01*
Y670172D01*
X1325497Y670463D01*
X1325934Y670172D01*
Y669588D01*
X1325497Y669297D01*
G01X1338194Y672504D02*
X1339503Y671046D01*
X1341032Y670172D01*
X1342997Y669880D01*
X1344962Y670463D01*
X1346490Y671630D01*
X1347582Y673671D01*
X1347800Y676005D01*
X1347364Y678338D01*
X1346272Y679797D01*
X1344743Y680963D01*
X1343215Y681255D01*
X1341687Y680963D01*
X1339722Y679797D01*
X1340377Y687380D01*
X1346272D01*
G01X1451944Y635230D02*
Y652730D01*
X1456310D01*
X1458057Y651855D01*
X1459367Y650688D01*
X1460459Y648939D01*
X1461332Y646896D01*
X1461550Y643980D01*
X1461332Y641063D01*
X1460459Y639021D01*
X1459367Y637271D01*
X1458057Y636105D01*
X1456310Y635230D01*
X1451944D01*
G01X1469880D02*
Y652730D01*
X1475120D01*
X1476867Y651855D01*
X1478177Y649813D01*
X1478614Y647480D01*
X1478177Y645147D01*
X1477085Y643397D01*
X1475120Y642521D01*
X1469880D01*
G01X1439247Y722030D02*
Y704530D01*
G01X1434225Y722030D02*
X1444269D01*
G01X1456747Y704530D02*
Y712405D01*
X1452380Y722030D01*
G01X1461114D02*
X1456747Y712405D01*
G01X1469880Y704530D02*
Y722030D01*
X1475120D01*
X1476867Y721155D01*
X1478177Y719113D01*
X1478614Y716780D01*
X1478177Y714447D01*
X1477085Y712697D01*
X1475120Y711821D01*
X1469880D01*
G01X1496114Y704530D02*
X1487380D01*
Y722030D01*
X1496114D01*
G01X1492620Y713572D02*
X1487380D01*
G01X1451944Y669880D02*
Y687380D01*
X1456310D01*
X1458057Y686505D01*
X1459367Y685338D01*
X1460459Y683589D01*
X1461332Y681546D01*
X1461550Y678630D01*
X1461332Y675713D01*
X1460459Y673671D01*
X1459367Y671921D01*
X1458057Y670755D01*
X1456310Y669880D01*
X1451944D01*
G01X1469880D02*
Y687380D01*
X1475120D01*
X1476867Y686505D01*
X1478177Y684463D01*
X1478614Y682130D01*
X1478177Y679797D01*
X1477085Y678047D01*
X1475120Y677171D01*
X1469880D01*
G01X1539880Y704530D02*
Y722030D01*
X1545339D01*
X1547085Y721155D01*
X1548177Y719988D01*
X1548614Y717655D01*
X1548177Y715321D01*
X1546867Y713863D01*
X1545339Y712988D01*
X1539880D01*
G01X1545339D02*
X1548614Y704530D01*
G01X1558472Y712405D02*
X1565459D01*
X1564804Y714447D01*
X1563712Y715613D01*
X1562184Y716196D01*
X1560655Y715905D01*
X1559345Y715030D01*
X1558472Y712988D01*
X1558035Y711238D01*
Y709488D01*
X1558472Y707738D01*
X1559564Y705988D01*
X1560874Y704822D01*
X1562402Y704530D01*
X1563930Y705113D01*
X1565459Y706863D01*
G01X1577937Y704530D02*
Y719405D01*
X1578374Y720863D01*
X1579247Y721738D01*
X1580557Y722030D01*
X1581867Y721447D01*
X1582522Y719988D01*
G01X1579902Y715030D02*
X1575535D01*
G01X1596747Y703947D02*
X1596310Y704238D01*
Y704822D01*
X1596747Y705113D01*
X1597184Y704822D01*
Y704238D01*
X1596747Y703947D01*
G01X1627380Y704530D02*
Y722030D01*
X1632620D01*
X1634367Y721155D01*
X1635677Y719113D01*
X1636114Y716780D01*
X1635677Y714447D01*
X1634585Y712697D01*
X1632620Y711821D01*
X1627380D01*
G01X1649247Y704530D02*
Y722030D01*
G01X1670677Y704530D02*
Y716196D01*
G01Y714155D02*
X1669804Y715321D01*
X1668493Y715905D01*
X1666965Y716196D01*
X1665437Y715613D01*
X1664127Y714447D01*
X1663253Y712697D01*
X1662817Y710363D01*
X1663253Y708030D01*
X1664127Y706280D01*
X1665437Y705113D01*
X1666965Y704530D01*
X1668493Y704822D01*
X1669804Y705696D01*
X1670677Y706863D01*
G01X1680535Y704530D02*
Y716196D01*
G01Y713280D02*
X1681409Y714738D01*
X1682719Y715905D01*
X1684465Y716196D01*
X1685993Y715905D01*
X1687304Y714738D01*
X1687959Y712697D01*
Y704530D01*
G01X1698472Y712405D02*
X1705459D01*
X1704804Y714447D01*
X1703712Y715613D01*
X1702184Y716196D01*
X1700655Y715905D01*
X1699345Y715030D01*
X1698472Y712988D01*
X1698035Y711238D01*
Y709488D01*
X1698472Y707738D01*
X1699564Y705988D01*
X1700874Y704822D01*
X1702402Y704530D01*
X1703930Y705113D01*
X1705459Y706863D01*
G01X1609880Y652730D02*
Y635230D01*
X1618614D01*
G01X1631310D02*
X1631747Y639021D01*
X1632402Y642230D01*
X1633275Y645147D01*
X1634367Y648355D01*
X1636114Y652730D01*
X1627380D01*
G01X1609880Y687380D02*
Y669880D01*
X1618614D01*
G01X1631310D02*
X1631747Y673671D01*
X1632402Y676880D01*
X1633275Y679797D01*
X1634367Y683005D01*
X1636114Y687380D01*
X1627380D01*
G01X1744744Y703947D02*
X1754350Y716780D01*
G01X1749547Y719113D02*
Y701613D01*
G01X1754350Y703947D02*
X1744744Y716780D01*
G01X1742997Y710363D02*
X1756097D01*
G01X1781709D02*
X1787385D01*
G01X1814744Y704530D02*
Y722030D01*
X1819110D01*
X1820857Y721155D01*
X1822167Y719988D01*
X1823259Y718239D01*
X1824132Y716196D01*
X1824350Y713280D01*
X1824132Y710363D01*
X1823259Y708321D01*
X1822167Y706571D01*
X1820857Y705405D01*
X1819110Y704530D01*
X1814744D01*
G01X1833772Y712405D02*
X1840759D01*
X1840104Y714447D01*
X1839012Y715613D01*
X1837484Y716196D01*
X1835955Y715905D01*
X1834645Y715030D01*
X1833772Y712988D01*
X1833335Y711238D01*
Y709488D01*
X1833772Y707738D01*
X1834864Y705988D01*
X1836174Y704822D01*
X1837702Y704530D01*
X1839230Y705113D01*
X1840759Y706863D01*
G01X1850835Y704530D02*
Y716196D01*
G01Y713280D02*
X1851709Y714738D01*
X1853019Y715905D01*
X1854765Y716196D01*
X1856293Y715905D01*
X1857604Y714738D01*
X1858259Y712697D01*
Y704530D01*
G01X1872047D02*
X1870737Y704822D01*
X1869427Y705988D01*
X1868553Y708030D01*
X1868117Y710363D01*
X1868553Y712697D01*
X1869427Y714738D01*
X1870737Y715905D01*
X1872047Y716196D01*
X1873357Y715905D01*
X1874667Y714738D01*
X1875540Y712697D01*
X1875759Y710363D01*
X1875540Y708030D01*
X1874667Y705988D01*
X1873357Y704822D01*
X1872047Y704530D01*
G01X1889547Y722030D02*
Y704530D01*
G01X1886490Y716196D02*
X1892604D01*
G01X1903772Y712405D02*
X1910759D01*
X1910104Y714447D01*
X1909012Y715613D01*
X1907484Y716196D01*
X1905955Y715905D01*
X1904645Y715030D01*
X1903772Y712988D01*
X1903335Y711238D01*
Y709488D01*
X1903772Y707738D01*
X1904864Y705988D01*
X1906174Y704822D01*
X1907702Y704530D01*
X1909230Y705113D01*
X1910759Y706863D01*
G01X1921272Y706571D02*
X1922364Y705405D01*
X1923892Y704530D01*
X1925202D01*
X1926512Y705113D01*
X1927385Y705988D01*
X1927822Y707154D01*
X1927604Y708905D01*
X1926730Y709780D01*
X1922800Y711530D01*
X1921927Y713572D01*
X1922364Y715030D01*
X1923237Y715905D01*
X1924547Y716196D01*
X1925857Y715905D01*
X1927167Y715030D01*
G01X1959547Y722030D02*
Y704530D01*
G01X1956490Y716196D02*
X1962604D01*
G01X1973335Y704530D02*
Y722030D01*
G01Y713572D02*
X1974427Y715030D01*
X1975519Y715905D01*
X1977265Y716196D01*
X1978575Y715905D01*
X1980104Y714738D01*
X1980759Y712988D01*
Y704530D01*
G01X1998477D02*
Y716196D01*
G01Y714155D02*
X1997604Y715321D01*
X1996293Y715905D01*
X1994765Y716196D01*
X1993237Y715613D01*
X1991927Y714447D01*
X1991053Y712697D01*
X1990617Y710363D01*
X1991053Y708030D01*
X1991927Y706280D01*
X1993237Y705113D01*
X1994765Y704530D01*
X1996293Y704822D01*
X1997604Y705696D01*
X1998477Y706863D01*
G01X2012047Y722030D02*
Y704530D01*
G01X2008990Y716196D02*
X2015104D01*
G01X2047047Y722030D02*
Y704530D01*
G01X2043990Y716196D02*
X2050104D01*
G01X2060835Y704530D02*
Y722030D01*
G01Y713572D02*
X2061927Y715030D01*
X2063019Y715905D01*
X2064765Y716196D01*
X2066075Y715905D01*
X2067604Y714738D01*
X2068259Y712988D01*
Y704530D01*
G01X2082047Y716196D02*
Y704530D01*
G01Y720863D02*
X2081610Y721155D01*
Y721738D01*
X2082047Y722030D01*
X2082484Y721738D01*
Y721155D01*
X2082047Y720863D01*
G01X2096272Y706571D02*
X2097364Y705405D01*
X2098892Y704530D01*
X2100202D01*
X2101512Y705113D01*
X2102385Y705988D01*
X2102822Y707154D01*
X2102604Y708905D01*
X2101730Y709780D01*
X2097800Y711530D01*
X2096927Y713572D01*
X2097364Y715030D01*
X2098237Y715905D01*
X2099547Y716196D01*
X2100857Y715905D01*
X2102167Y715030D01*
G01X2131927Y722030D02*
X2137167D01*
G01X2134547D02*
Y704530D01*
G01X2131927D02*
X2137167D01*
G01X2145497D02*
Y716196D01*
G01Y712988D02*
X2146152Y714447D01*
X2147244Y715613D01*
X2148772Y716196D01*
X2150300Y715613D01*
X2151392Y714447D01*
X2152047Y712988D01*
Y704530D01*
G01Y712988D02*
X2152702Y714447D01*
X2153793Y715613D01*
X2155322Y716196D01*
X2156850Y715613D01*
X2157942Y714447D01*
X2158597Y712697D01*
Y704530D01*
G01X2165617Y698697D02*
Y716196D01*
G01Y713572D02*
X2166709Y715030D01*
X2167800Y715905D01*
X2169547Y716196D01*
X2171075Y715905D01*
X2172604Y714447D01*
X2173259Y712405D01*
X2173477Y710363D01*
X2173259Y708321D01*
X2172604Y706280D01*
X2171293Y705113D01*
X2169547Y704530D01*
X2168019Y704822D01*
X2166490Y705696D01*
X2165617Y706863D01*
G01X2183772Y712405D02*
X2190759D01*
X2190104Y714447D01*
X2189012Y715613D01*
X2187484Y716196D01*
X2185955Y715905D01*
X2184645Y715030D01*
X2183772Y712988D01*
X2183335Y711238D01*
Y709488D01*
X2183772Y707738D01*
X2184864Y705988D01*
X2186174Y704822D01*
X2187702Y704530D01*
X2189230Y705113D01*
X2190759Y706863D01*
G01X2208477Y722030D02*
Y704530D01*
G01Y707154D02*
X2207604Y705696D01*
X2206293Y704822D01*
X2204765Y704530D01*
X2203019Y705113D01*
X2201709Y706571D01*
X2200835Y708321D01*
X2200617Y710363D01*
X2200835Y712405D01*
X2201709Y714155D01*
X2203019Y715613D01*
X2204765Y716196D01*
X2206293Y715905D01*
X2207385Y715321D01*
X2208477Y714155D01*
G01X2225977Y704530D02*
Y716196D01*
G01Y714155D02*
X2225104Y715321D01*
X2223793Y715905D01*
X2222265Y716196D01*
X2220737Y715613D01*
X2219427Y714447D01*
X2218553Y712697D01*
X2218117Y710363D01*
X2218553Y708030D01*
X2219427Y706280D01*
X2220737Y705113D01*
X2222265Y704530D01*
X2223793Y704822D01*
X2225104Y705696D01*
X2225977Y706863D01*
G01X2235835Y704530D02*
Y716196D01*
G01Y713280D02*
X2236709Y714738D01*
X2238019Y715905D01*
X2239765Y716196D01*
X2241293Y715905D01*
X2242604Y714738D01*
X2243259Y712697D01*
Y704530D01*
G01X2260540Y714738D02*
X2259012Y715905D01*
X2257702Y716196D01*
X2255955Y715613D01*
X2254645Y714447D01*
X2253772Y712405D01*
X2253553Y710363D01*
X2253772Y708321D01*
X2254645Y706571D01*
X2255955Y705113D01*
X2257702Y704530D01*
X2259230Y705113D01*
X2260540Y706280D01*
G01X2271272Y712405D02*
X2278259D01*
X2277604Y714447D01*
X2276512Y715613D01*
X2274984Y716196D01*
X2273455Y715905D01*
X2272145Y715030D01*
X2271272Y712988D01*
X2270835Y711238D01*
Y709488D01*
X2271272Y707738D01*
X2272364Y705988D01*
X2273674Y704822D01*
X2275202Y704530D01*
X2276730Y705113D01*
X2278259Y706863D01*
G01X1819547Y681546D02*
Y669880D01*
G01Y686213D02*
X1819110Y686505D01*
Y687088D01*
X1819547Y687380D01*
X1819984Y687088D01*
Y686505D01*
X1819547Y686213D01*
G01X1833772Y671921D02*
X1834864Y670755D01*
X1836392Y669880D01*
X1837702D01*
X1839012Y670463D01*
X1839885Y671338D01*
X1840322Y672504D01*
X1840104Y674255D01*
X1839230Y675130D01*
X1835300Y676880D01*
X1834427Y678922D01*
X1834864Y680380D01*
X1835737Y681255D01*
X1837047Y681546D01*
X1838357Y681255D01*
X1839667Y680380D01*
G01X1867025Y669880D02*
Y687380D01*
X1877069Y669880D01*
Y687380D01*
G01X1889547Y669880D02*
X1887800Y670172D01*
X1886272Y671338D01*
X1884962Y673088D01*
X1884088Y675130D01*
X1883652Y677463D01*
Y679797D01*
X1884088Y682130D01*
X1884962Y684172D01*
X1886272Y685921D01*
X1887800Y687088D01*
X1889547Y687380D01*
X1891293Y687088D01*
X1892822Y685921D01*
X1894132Y684172D01*
X1895006Y682130D01*
X1895442Y679797D01*
Y677463D01*
X1895006Y675130D01*
X1894132Y673088D01*
X1892822Y671338D01*
X1891293Y670172D01*
X1889547Y669880D01*
G01X1907047Y687380D02*
Y669880D01*
G01X1902025Y687380D02*
X1912069D01*
G01X1938335Y681546D02*
Y673380D01*
X1939209Y671338D01*
X1940519Y670172D01*
X1942047Y669880D01*
X1943575Y670172D01*
X1944885Y671338D01*
X1945759Y673380D01*
G01Y669880D02*
Y681546D01*
G01X1956272Y671921D02*
X1957364Y670755D01*
X1958892Y669880D01*
X1960202D01*
X1961512Y670463D01*
X1962385Y671338D01*
X1962822Y672504D01*
X1962604Y674255D01*
X1961730Y675130D01*
X1957800Y676880D01*
X1956927Y678922D01*
X1957364Y680380D01*
X1958237Y681255D01*
X1959547Y681546D01*
X1960857Y681255D01*
X1962167Y680380D01*
G01X1973772Y677755D02*
X1980759D01*
X1980104Y679797D01*
X1979012Y680963D01*
X1977484Y681546D01*
X1975955Y681255D01*
X1974645Y680380D01*
X1973772Y678338D01*
X1973335Y676588D01*
Y674838D01*
X1973772Y673088D01*
X1974864Y671338D01*
X1976174Y670172D01*
X1977702Y669880D01*
X1979230Y670463D01*
X1980759Y672213D01*
G01X1998477Y687380D02*
Y669880D01*
G01Y672504D02*
X1997604Y671046D01*
X1996293Y670172D01*
X1994765Y669880D01*
X1993019Y670463D01*
X1991709Y671921D01*
X1990835Y673671D01*
X1990617Y675713D01*
X1990835Y677755D01*
X1991709Y679505D01*
X1993019Y680963D01*
X1994765Y681546D01*
X1996293Y681255D01*
X1997385Y680671D01*
X1998477Y679505D01*
G01X3937Y0D02*
X116260D01*
G01X0Y3937D02*
G03X3937Y0I3937J0D01*
G01X0Y723480D02*
Y3937D01*
G01X416Y725241D02*
G03X0Y723480I3521J-1761D01*
G01X18597Y761603D02*
X416Y725241D01*
G01X22118Y763780D02*
G03X18597Y761603I1J-3937D01*
G01X386149Y763780D02*
X22118D01*
G01X120197Y3937D02*
Y429331D01*
G01X116260Y0D02*
G03X120197Y3937I0J3937D01*
G01X128071D02*
G03X132008Y0I3937J0D01*
G01X128071Y43308D02*
G03X120197I-3937J0D01*
G01X132008Y0D02*
X275709D01*
G01X128071Y3937D02*
Y43308D01*
G01X120197Y74016D02*
G03X128071I3937J0D01*
G01D02*
Y425394D01*
G01X124134Y433268D02*
X283583D01*
G01X124134D02*
G03X120197Y429331I0J-3937D01*
G01X188504Y425394D02*
X128071D01*
G01X152497Y21054D02*
G03I-4291J0D01*
G01X188504Y425394D02*
G03Y433268I0J3937D01*
G01X275709Y0D02*
G03X279646Y3937I0J3937D01*
G01X287520Y43308D02*
G03X279646I-3937J0D01*
G01Y3937D02*
Y43308D01*
G01Y74016D02*
G03X287520I3937J0D01*
G01X279646D02*
Y425394D01*
G01X265438Y405580D02*
G03I-4291J0D01*
G01X287520Y429331D02*
G03X283583Y433268I-3937J0D01*
G01X219213D02*
G03Y425394I0J-3937D01*
G01X279646D02*
X219213D01*
G01X291457Y0D02*
X921260D01*
G01X287520Y3937D02*
G03X291457Y0I3937J0D01*
G01X287520Y429331D02*
Y3937D01*
G01X408268Y188976D02*
Y723480D01*
G01Y188976D02*
G03X412205I1968J0D01*
G01X564173D02*
X412205D01*
G01X416142Y348379D02*
Y196851D01*
G01D02*
X560237D01*
G01X416142Y348379D02*
G03X408268I-3937J0D01*
G01Y379088D02*
G03X416142I3937J0D01*
G01Y688303D02*
Y379088D01*
G01Y688303D02*
G03X408268I-3937J0D01*
G01X389671Y761603D02*
G03X386149Y763780I-3522J-1760D01*
G01X407852Y725241D02*
X389671Y761603D01*
G01X408268Y723480D02*
G03X407852Y725241I-3937J0D01*
G01X524242Y763780D02*
X403757D01*
G01D02*
G03X400235Y758082I0J-3937D01*
G01X408268Y719012D02*
G03X416142I3937J0D01*
G01Y723480D02*
G03X414895Y728763I-11811J1D01*
G01X400235Y758082D02*
X414895Y728763D01*
G01X416142Y723480D02*
Y719012D01*
G01X490789Y356293D02*
G03I-4291J0D01*
G01X564173Y188976D02*
G03X568110I1968J0D01*
G01Y589622D02*
Y188976D01*
G01X560237Y261975D02*
Y196851D01*
G01X568111Y261975D02*
G03X560237I-3937J0D01*
G01Y292684D02*
G03X568111I3937J0D01*
G01X560237Y551040D02*
Y292684D01*
G01X568111Y551040D02*
G03X560237I-3937J0D01*
G01X568526Y591382D02*
G03X568110Y589622I3521J-1761D01*
G01X586707Y627745D02*
X568526Y591382D01*
G01X560237Y581748D02*
G03X568111I3937J0D01*
G01X561484Y594905D02*
G03X560237Y589622I10564J-5282D01*
G01D02*
Y581748D01*
G01X579665Y631267D02*
X561484Y594904D01*
G01X524242Y763780D02*
G03X532116I3937J0D01*
G01X834646D02*
X532116D01*
G01X590228Y629921D02*
G03X586707Y627745I0J-3937D01*
G01X842520Y629921D02*
X590228D01*
G01X590229Y637796D02*
G03X579665Y631268I0J-11812D01*
G01X590229Y637796D02*
X838583D01*
G01X842520Y629921D02*
G03X846457Y633858I0J3937D01*
G01Y759843D02*
Y633858D01*
G01X838583Y637796D02*
Y709449D01*
G01X850394Y763780D02*
G03X846457Y759843I0J-3937D01*
G01X903079Y763780D02*
X850394D01*
G01X812123Y734367D02*
G03I-4292J0D01*
G01X838583Y759843D02*
G03X834646Y763780I-3937J0D01*
G01X838583Y740158D02*
G03X846457I3937J0D01*
G01Y709449D02*
G03X838583I-3937J0D01*
G01Y740158D02*
Y759843D01*
G01X921260Y0D02*
G03X925197Y3937I0J3937D01*
G01D02*
Y723480D01*
G01X906600Y761603D02*
G03X903079Y763780I-3522J-1760D01*
G01X924781Y725241D02*
X906600Y761603D01*
G01X925197Y723480D02*
G03X924781Y725241I-3937J0D01*
G54D12*
G01X83192Y557180D02*
X85815D01*
G01X83192Y555580D02*
X86135D01*
G01X83192D02*
X86135D01*
G01X83192Y557180D02*
X85815D01*
G54D13*
G01X351330Y133798D02*
X347414Y152213D01*
G01X351330Y133798D02*
X347414Y152213D01*
G01X351330Y133798D02*
X347414Y152213D01*
G01X352481Y134275D02*
X352123Y135961D01*
G01X351330Y133798D02*
X347414Y152213D01*
G01X359662Y123221D02*
X352481Y134275D01*
G01X358776Y122335D02*
X351330Y133798D01*
G01D02*
X347414Y152213D01*
G01X352481Y134275D02*
X352123Y135961D01*
G01X358776Y122335D02*
X351330Y133798D01*
G01X359662Y123221D02*
X352481Y134275D01*
G01X366432Y144583D02*
X352831Y209003D01*
G01X367583Y145065D02*
X354083Y209005D01*
G01X367583Y145065D02*
X354083Y209005D01*
G01X366432Y144583D02*
X352831Y209003D01*
G01X350895Y193178D02*
X347966Y207808D01*
G01X352146Y193170D02*
X349217Y207804D01*
G01X349416Y186251D02*
X350895Y193178D01*
G01X350669Y186250D02*
X352146Y193170D01*
G01X357107Y150061D02*
X349416Y186251D01*
G01X358258Y150538D02*
X350669Y186250D01*
G01X352146Y193170D02*
X349217Y207804D01*
G01X350895Y193178D02*
X347966Y207808D01*
G01X350669Y186250D02*
X352146Y193170D01*
G01X349416Y186251D02*
X350895Y193178D01*
G01X358258Y150538D02*
X350669Y186250D01*
G01X357107Y150061D02*
X349416Y186251D01*
G01X346848Y193347D02*
X343813Y207618D01*
G01X345595Y193347D02*
X342560Y207618D01*
G01X343383Y177058D02*
X346848Y193347D01*
G01X342130Y177058D02*
X345595Y193347D01*
G01X348613Y152467D02*
X343383Y177058D01*
G01X347414Y152213D02*
X342130Y177058D01*
G01X349580Y147919D02*
X349221Y149606D01*
G01X350547Y143371D02*
X350188Y145058D01*
G01X351514Y138823D02*
X351155Y140510D01*
G01X345595Y193347D02*
X342560Y207618D01*
G01X346848Y193347D02*
X343813Y207618D01*
G01X342130Y177058D02*
X345595Y193347D01*
G01X343383Y177058D02*
X346848Y193347D01*
G01X347414Y152213D02*
X342130Y177058D01*
G01X348613Y152467D02*
X343383Y177058D01*
G01X349580Y147919D02*
X349221Y149606D01*
G01X350547Y143371D02*
X350188Y145058D01*
G01X351514Y138823D02*
X351155Y140510D01*
G01X361495Y228223D02*
X349444Y285473D01*
G01X362748Y228222D02*
X350596Y285950D01*
G01X362748Y228222D02*
X350596Y285950D01*
G01X361495Y228223D02*
X349444Y285473D01*
G01X356697Y227679D02*
X345038Y283661D01*
G01X357949Y227680D02*
X346163Y284269D01*
G01X352831Y209003D02*
X356697Y227679D01*
G01X354083Y209005D02*
X357949Y227680D01*
G01D02*
X346163Y284269D01*
G01X356697Y227679D02*
X345038Y283661D01*
G01X354083Y209005D02*
X357949Y227680D01*
G01X352831Y209003D02*
X356697Y227679D01*
G01X313425Y275975D02*
X310671Y278729D01*
G01X313933Y277200D02*
X311179Y279954D01*
G01X336026Y275975D02*
X313425D01*
G01X336534Y277200D02*
X313933D01*
G01X343545Y268455D02*
X336026Y275975D01*
G01X344674Y269059D02*
X336534Y277200D01*
G01X351890Y226757D02*
X343545Y268455D01*
G01X353141Y226753D02*
X344674Y269059D01*
G01X347966Y207808D02*
X351890Y226757D01*
G01X349217Y207804D02*
X353141Y226753D01*
G01X313933Y277200D02*
X311179Y279954D01*
G01X313425Y275975D02*
X310671Y278729D01*
G01X336534Y277200D02*
X313933D01*
G01X336026Y275975D02*
X313425D01*
G01X344674Y269059D02*
X336534Y277200D01*
G01X343545Y268455D02*
X336026Y275975D01*
G01X353141Y226753D02*
X344674Y269059D01*
G01X351890Y226757D02*
X343545Y268455D01*
G01X349217Y207804D02*
X353141Y226753D01*
G01X347966Y207808D02*
X351890Y226757D01*
G01X302835Y266146D02*
X303410D01*
G01X302327Y267371D02*
X303411D01*
G01X302088Y265399D02*
X302835Y266146D01*
G01X300863Y265907D02*
X302327Y267371D01*
G01X302088Y260612D02*
Y265399D01*
G01X300863Y260104D02*
Y265907D01*
G01X303600Y259100D02*
X302088Y260612D01*
G01X303092Y257875D02*
X300863Y260104D01*
G01X307567Y259100D02*
X303600D01*
G01X308075Y257875D02*
X303092D01*
G01X309692Y261225D02*
X307567Y259100D01*
G01X310200Y260000D02*
X308075Y257875D01*
G01X334508Y261225D02*
X309692D01*
G01X334000Y260000D02*
X310200D01*
G01X340768Y254966D02*
X334508Y261225D01*
G01X339644Y254356D02*
X334000Y260000D01*
G01X343446Y242318D02*
X340768Y254966D01*
G01X346056Y224070D02*
X339644Y254356D01*
G01X344409Y237769D02*
X344052Y239457D01*
G01X346056Y224070D02*
X339644Y254356D01*
G01X345372Y233220D02*
X345015Y234908D01*
G01X346056Y224070D02*
X339644Y254356D01*
G01X346335Y228671D02*
X345978Y230359D01*
G01X346056Y224070D02*
X339644Y254356D01*
G01X347309Y224070D02*
X346941Y225809D01*
G01X346056Y224070D02*
X339644Y254356D01*
G01X343813Y207618D02*
X347309Y224070D01*
G01X342560Y207618D02*
X346056Y224070D01*
G01X302327Y267371D02*
X303411D01*
G01X302835Y266146D02*
X303410D01*
G01X300863Y265907D02*
X302327Y267371D01*
G01X302088Y265399D02*
X302835Y266146D01*
G01X300863Y260104D02*
Y265907D01*
G01X302088Y260612D02*
Y265399D01*
G01X303092Y257875D02*
X300863Y260104D01*
G01X303600Y259100D02*
X302088Y260612D01*
G01X308075Y257875D02*
X303092D01*
G01X307567Y259100D02*
X303600D01*
G01X310200Y260000D02*
X308075Y257875D01*
G01X309692Y261225D02*
X307567Y259100D01*
G01X334000Y260000D02*
X310200D01*
G01X334508Y261225D02*
X309692D01*
G01X339644Y254356D02*
X334000Y260000D01*
G01X340768Y254966D02*
X334508Y261225D01*
G01X346056Y224070D02*
X339644Y254356D01*
G01X343446Y242318D02*
X340768Y254966D01*
G01X344409Y237769D02*
X344052Y239457D01*
G01X345372Y233220D02*
X345015Y234908D01*
G01X346335Y228671D02*
X345978Y230359D01*
G01X347309Y224070D02*
X346941Y225809D01*
G01X342560Y207618D02*
X346056Y224070D01*
G01X343813Y207618D02*
X347309Y224070D01*
G01X352889Y331721D02*
X347931Y355047D01*
G01X354040Y332198D02*
X349082Y355524D01*
G01X373902Y299358D02*
X352889Y331721D01*
G01X375053Y299835D02*
X354040Y332198D01*
G01D02*
X349082Y355524D01*
G01X352889Y331721D02*
X347931Y355047D01*
G01X375053Y299835D02*
X354040Y332198D01*
G01X373902Y299358D02*
X352889Y331721D01*
G01X336225Y349275D02*
X328600Y356900D01*
G01X340425Y349275D02*
X336225D01*
G01X343445Y346255D02*
X340425Y349275D01*
G01X344403Y347031D02*
X340933Y350500D01*
G01X345780Y342662D02*
X343445Y346255D01*
G01X346931Y343139D02*
X344403Y347031D01*
G01X348431Y330185D02*
X345780Y342662D01*
G01X349582Y330662D02*
X346931Y343139D01*
G01X369483Y297764D02*
X348431Y330185D01*
G01X370636Y298239D02*
X349582Y330662D01*
G01X336225Y349275D02*
X328600Y356900D01*
G01X340425Y349275D02*
X336225D01*
G01X344403Y347031D02*
X340933Y350500D01*
G01X343445Y346255D02*
X340425Y349275D01*
G01X346931Y343139D02*
X344403Y347031D01*
G01X345780Y342662D02*
X343445Y346255D01*
G01X349582Y330662D02*
X346931Y343139D01*
G01X348431Y330185D02*
X345780Y342662D01*
G01X370636Y298239D02*
X349582Y330662D01*
G01X369483Y297764D02*
X348431Y330185D01*
G01X310200Y341700D02*
X305375D01*
G01X310708Y342925D02*
X305434D01*
G01X313499Y338400D02*
X310200Y341700D01*
G01X314007Y339625D02*
X310708Y342925D01*
G01X329033Y338400D02*
X313499D01*
G01X328525Y339625D02*
X314007D01*
G01X332525Y341892D02*
X329033Y338400D01*
G01X331300Y342400D02*
X328525Y339625D01*
G01X332525Y343592D02*
Y341892D01*
G01X331300Y344100D02*
Y342400D01*
G01X333708Y344775D02*
X332525Y343592D01*
G01X333200Y346000D02*
X331300Y344100D01*
G01X335792Y344775D02*
X333708D01*
G01X336300Y346000D02*
X333200D01*
G01X339325Y341242D02*
X335792Y344775D01*
G01X340283Y342018D02*
X336300Y346000D01*
G01X342289Y336677D02*
X339325Y341242D01*
G01X343440Y337154D02*
X340283Y342018D01*
G01X344069Y328309D02*
X342289Y336677D01*
G01X345220Y328786D02*
X343440Y337154D01*
G01X365112Y295918D02*
X344069Y328309D01*
G01X366265Y296393D02*
X345220Y328786D01*
G01X310708Y342925D02*
X305434D01*
G01X310200Y341700D02*
X305375D01*
G01X314007Y339625D02*
X310708Y342925D01*
G01X313499Y338400D02*
X310200Y341700D01*
G01X328525Y339625D02*
X314007D01*
G01X329033Y338400D02*
X313499D01*
G01X331300Y342400D02*
X328525Y339625D01*
G01X332525Y341892D02*
X329033Y338400D01*
G01X331300Y344100D02*
Y342400D01*
G01X332525Y343592D02*
Y341892D01*
G01X333200Y346000D02*
X331300Y344100D01*
G01X333708Y344775D02*
X332525Y343592D01*
G01X336300Y346000D02*
X333200D01*
G01X335792Y344775D02*
X333708D01*
G01X340283Y342018D02*
X336300Y346000D01*
G01X339325Y341242D02*
X335792Y344775D01*
G01X343440Y337154D02*
X340283Y342018D01*
G01X342289Y336677D02*
X339325Y341242D01*
G01X345220Y328786D02*
X343440Y337154D01*
G01X344069Y328309D02*
X342289Y336677D01*
G01X366265Y296393D02*
X345220Y328786D01*
G01X365112Y295918D02*
X344069Y328309D01*
G01X314529Y329129D02*
X308704D01*
G01X314021Y330354D02*
X308705D01*
G01X316900Y331500D02*
X314529Y329129D01*
G01X316392Y332725D02*
X314021Y330354D01*
G01X328499Y331500D02*
X316900D01*
G01X329007Y332725D02*
X316392D01*
G01X334201Y325800D02*
X328499Y331500D01*
G01X334709Y327025D02*
X329007Y332725D01*
G01X338000Y325800D02*
X334201D01*
G01X338508Y327025D02*
X334709D01*
G01X343844Y319956D02*
X338000Y325800D01*
G01X344802Y320731D02*
X338508Y327025D01*
G01X360838Y293734D02*
X343844Y319956D01*
G01X361991Y294208D02*
X344802Y320731D01*
G01X314021Y330354D02*
X308705D01*
G01X314529Y329129D02*
X308704D01*
G01X316392Y332725D02*
X314021Y330354D01*
G01X316900Y331500D02*
X314529Y329129D01*
G01X329007Y332725D02*
X316392D01*
G01X328499Y331500D02*
X316900D01*
G01X334709Y327025D02*
X329007Y332725D01*
G01X334201Y325800D02*
X328499Y331500D01*
G01X338508Y327025D02*
X334709D01*
G01X338000Y325800D02*
X334201D01*
G01X344802Y320731D02*
X338508Y327025D01*
G01X343844Y319956D02*
X338000Y325800D01*
G01X361991Y294208D02*
X344802Y320731D01*
G01X360838Y293734D02*
X343844Y319956D01*
G01X309670Y316530D02*
X305405D01*
G01X310178Y317755D02*
X305404D01*
G01X313200Y313000D02*
X309670Y316530D01*
G01X313708Y314225D02*
X310178Y317755D01*
G01X328400Y313000D02*
X313200D01*
G01X327892Y314225D02*
X313708D01*
G01X333975Y318575D02*
X328400Y313000D01*
G01X333467Y319800D02*
X327892Y314225D01*
G01X336625Y318575D02*
X333975D01*
G01X337133Y319800D02*
X333467D01*
G01X341477Y313723D02*
X336625Y318575D01*
G01X342343Y314590D02*
X337133Y319800D01*
G01X342435Y314499D02*
X342344Y314590D01*
G01X356501Y290587D02*
X341477Y313723D01*
G01X357653Y291063D02*
X342435Y314499D01*
G01X310178Y317755D02*
X305404D01*
G01X309670Y316530D02*
X305405D01*
G01X313708Y314225D02*
X310178Y317755D01*
G01X313200Y313000D02*
X309670Y316530D01*
G01X327892Y314225D02*
X313708D01*
G01X328400Y313000D02*
X313200D01*
G01X333467Y319800D02*
X327892Y314225D01*
G01X333975Y318575D02*
X328400Y313000D01*
G01X337133Y319800D02*
X333467D01*
G01X336625Y318575D02*
X333975D01*
G01X342343Y314590D02*
X337133Y319800D01*
G01X341477Y313723D02*
X336625Y318575D01*
G01X342435Y314499D02*
X342344Y314590D01*
G01X341477Y313723D02*
X336625Y318575D01*
G01X357653Y291063D02*
X342435Y314499D01*
G01X356501Y290587D02*
X341477Y313723D01*
G01X315630Y303930D02*
X308705D01*
G01X315122Y305155D02*
X308704D01*
G01X318000Y306300D02*
X315630Y303930D01*
G01X317492Y307525D02*
X315122Y305155D01*
G01X329000Y306300D02*
X318000D01*
G01X329508Y307525D02*
X317492D01*
G01X331050Y304250D02*
X329000Y306300D01*
G01X332275Y304758D02*
X329508Y307525D01*
G01X331050Y302050D02*
Y304250D01*
G01X332275Y302558D02*
Y304758D01*
G01X333300Y299800D02*
X331050Y302050D01*
G01X333808Y301025D02*
X332275Y302558D01*
G01X339667Y299800D02*
X333300D01*
G01X340175Y301025D02*
X333808D01*
G01X340916Y298550D02*
X339667Y299800D01*
G01X341873Y299327D02*
X340175Y301025D01*
G01X349444Y285473D02*
X340916Y298550D01*
G01X350596Y285950D02*
X341873Y299327D01*
G01X315122Y305155D02*
X308704D01*
G01X315630Y303930D02*
X308705D01*
G01X317492Y307525D02*
X315122Y305155D01*
G01X318000Y306300D02*
X315630Y303930D01*
G01X329508Y307525D02*
X317492D01*
G01X329000Y306300D02*
X318000D01*
G01X332275Y304758D02*
X329508Y307525D01*
G01X331050Y304250D02*
X329000Y306300D01*
G01X332275Y302558D02*
Y304758D01*
G01X331050Y302050D02*
Y304250D01*
G01X333808Y301025D02*
X332275Y302558D01*
G01X333300Y299800D02*
X331050Y302050D01*
G01X340175Y301025D02*
X333808D01*
G01X339667Y299800D02*
X333300D01*
G01X341873Y299327D02*
X340175Y301025D01*
G01X340916Y298550D02*
X339667Y299800D01*
G01X350596Y285950D02*
X341873Y299327D01*
G01X349444Y285473D02*
X340916Y298550D01*
G01X306870Y291330D02*
X305405D01*
G01X307378Y292555D02*
X305404D01*
G01X310800Y287400D02*
X306870Y291330D01*
G01X311308Y288625D02*
X307378Y292555D01*
G01X328800Y287400D02*
X310800D01*
G01X328292Y288625D02*
X311308D01*
G01X332025Y290625D02*
X328800Y287400D01*
G01X330800Y291133D02*
X328292Y288625D01*
G01X332025Y292525D02*
Y290625D01*
G01X330800Y293033D02*
Y291133D01*
G01X332975Y293475D02*
X332025Y292525D01*
G01X332467Y294700D02*
X330800Y293033D01*
G01X335225Y293475D02*
X332975D01*
G01X335733Y294700D02*
X332467D01*
G01X345038Y283661D02*
X335225Y293475D01*
G01X346163Y284269D02*
X335733Y294700D01*
G01X307378Y292555D02*
X305404D01*
G01X306870Y291330D02*
X305405D01*
G01X311308Y288625D02*
X307378Y292555D01*
G01X310800Y287400D02*
X306870Y291330D01*
G01X328292Y288625D02*
X311308D01*
G01X328800Y287400D02*
X310800D01*
G01X330800Y291133D02*
X328292Y288625D01*
G01X332025Y290625D02*
X328800Y287400D01*
G01X330800Y293033D02*
Y291133D01*
G01X332025Y292525D02*
Y290625D01*
G01X332467Y294700D02*
X330800Y293033D01*
G01X332975Y293475D02*
X332025Y292525D01*
G01X335733Y294700D02*
X332467D01*
G01X335225Y293475D02*
X332975D01*
G01X346163Y284269D02*
X335733Y294700D01*
G01X345038Y283661D02*
X335225Y293475D01*
G01X310671Y278729D02*
X308704D01*
G01X311179Y279954D02*
X308705D01*
G01X311179D02*
X308705D01*
G01X310671Y278729D02*
X308704D01*
G01X309970Y366930D02*
X305405D01*
G01X310478Y368155D02*
X305404D01*
G01X314300Y362600D02*
X309970Y366930D01*
G01X314808Y363825D02*
X310478Y368155D01*
G01X329100Y362600D02*
X314300D01*
G01X328592Y363825D02*
X314808D01*
G01X331900Y365400D02*
X329100Y362600D01*
G01X330675Y365908D02*
X328592Y363825D01*
G01X331900Y368200D02*
Y365400D01*
G01X330675Y368708D02*
Y365908D01*
G01X333200Y369500D02*
X331900Y368200D01*
G01X332692Y370725D02*
X330675Y368708D01*
G01X337200Y369500D02*
X333200D01*
G01X337708Y370725D02*
X332692D01*
G01X341037Y365663D02*
X337200Y369500D01*
G01X341995Y366439D02*
X337708Y370725D01*
G01X347931Y355047D02*
X341037Y365663D01*
G01X349082Y355524D02*
X341995Y366439D01*
G01X310478Y368155D02*
X305404D01*
G01X309970Y366930D02*
X305405D01*
G01X314808Y363825D02*
X310478Y368155D01*
G01X314300Y362600D02*
X309970Y366930D01*
G01X328592Y363825D02*
X314808D01*
G01X329100Y362600D02*
X314300D01*
G01X330675Y365908D02*
X328592Y363825D01*
G01X331900Y365400D02*
X329100Y362600D01*
G01X330675Y368708D02*
Y365908D01*
G01X331900Y368200D02*
Y365400D01*
G01X332692Y370725D02*
X330675Y368708D01*
G01X333200Y369500D02*
X331900Y368200D01*
G01X337708Y370725D02*
X332692D01*
G01X337200Y369500D02*
X333200D01*
G01X341995Y366439D02*
X337708Y370725D01*
G01X341037Y365663D02*
X337200Y369500D01*
G01X349082Y355524D02*
X341995Y366439D01*
G01X347931Y355047D02*
X341037Y365663D01*
G01X314330Y354330D02*
X308705D01*
G01X313822Y355555D02*
X308704D01*
G01X316900Y356900D02*
X314330Y354330D01*
G01X316392Y358125D02*
X313822Y355555D01*
G01X328600Y356900D02*
X316900D01*
G01X329108Y358125D02*
X316392D01*
G01X336733Y350500D02*
X329108Y358125D01*
G01X340933Y350500D02*
X336733D01*
G01X313822Y355555D02*
X308704D01*
G01X314330Y354330D02*
X308705D01*
G01X316392Y358125D02*
X313822Y355555D01*
G01X316900Y356900D02*
X314330Y354330D01*
G01X329108Y358125D02*
X316392D01*
G01X328600Y356900D02*
X316900D01*
G01X336733Y350500D02*
X329108Y358125D01*
G01X340933Y350500D02*
X336733D01*
G01X410168Y133816D02*
X405871Y136679D01*
G01X414866Y132876D02*
X410168Y133816D01*
G01X415106Y134078D02*
X410646Y134970D01*
G01X414984Y132853D02*
X414866Y132876D01*
G01X415106Y134078D02*
X410646Y134970D01*
G01X421010Y134078D02*
X415106D01*
G01X421010Y132853D02*
X414984D01*
G01X421010Y134078D02*
X415106D01*
G01X410168Y133816D02*
X405871Y136679D01*
G01X415106Y134078D02*
X410646Y134970D01*
G01X414866Y132876D02*
X410168Y133816D01*
G01X414984Y132853D02*
X414866Y132876D01*
G01X421010Y134078D02*
X415106D01*
G01X414984Y132853D02*
X414866Y132876D01*
G01X421010Y132853D02*
X414984D01*
G01X403858Y131161D02*
X387728Y155358D01*
G01X404741Y132046D02*
X388878Y155843D01*
G01X417205Y122297D02*
X403858Y131161D01*
G01X417682Y123451D02*
X404741Y132046D01*
G01X419203Y121897D02*
X417205Y122297D01*
G01X421206Y122746D02*
X417682Y123451D01*
G01X420966Y121544D02*
X419203Y121897D01*
G01X421206Y122746D02*
X417682Y123451D01*
G01X421084Y121521D02*
X420966Y121544D01*
G01X421206Y122746D02*
X417682Y123451D01*
G01X422776Y122746D02*
X421206D01*
G01X423284Y121521D02*
X421084D01*
G01X422776Y122746D02*
X421206D01*
G01X425809Y124046D02*
X423284Y121521D01*
G01X424584Y124554D02*
X422776Y122746D01*
G01X425809Y127273D02*
Y124046D01*
G01X424584Y127273D02*
Y124554D01*
G01X426664Y128128D02*
G03X425809Y127273I0J-855D01*
G01X426664Y129353D02*
G03X424584Y127273I0J-2080D01*
G01X428097Y128128D02*
X426664D01*
G01X428097Y129353D02*
X426664D01*
G01X404741Y132046D02*
X388878Y155843D01*
G01X403858Y131161D02*
X387728Y155358D01*
G01X417682Y123451D02*
X404741Y132046D01*
G01X417205Y122297D02*
X403858Y131161D01*
G01X421206Y122746D02*
X417682Y123451D01*
G01X419203Y121897D02*
X417205Y122297D01*
G01X420966Y121544D02*
X419203Y121897D01*
G01X421084Y121521D02*
X420966Y121544D01*
G01X422776Y122746D02*
X421206D01*
G01X421084Y121521D02*
X420966Y121544D01*
G01X423284Y121521D02*
X421084D01*
G01X424584Y124554D02*
X422776Y122746D01*
G01X425809Y124046D02*
X423284Y121521D01*
G01X424584Y127273D02*
Y124554D01*
G01X425809Y127273D02*
Y124046D01*
G01X426664Y129353D02*
G03X424584Y127273I0J-2080D01*
G01X426664Y128128D02*
G03X425809Y127273I0J-855D01*
G01X428097Y129353D02*
X426664D01*
G01X428097Y128128D02*
X426664D01*
G01X401921Y125216D02*
X383473Y152975D01*
G01X402806Y126099D02*
X384623Y153458D01*
G01X412370Y118247D02*
X401921Y125216D01*
G01X412848Y119401D02*
X402806Y126099D01*
G01X418723Y116977D02*
X412370Y118247D01*
G01X418845Y118202D02*
X412848Y119401D01*
G01X430135Y116977D02*
X418723D01*
G01X429627Y118202D02*
X418845D01*
G01X402806Y126099D02*
X384623Y153458D01*
G01X401921Y125216D02*
X383473Y152975D01*
G01X412848Y119401D02*
X402806Y126099D01*
G01X412370Y118247D02*
X401921Y125216D01*
G01X418845Y118202D02*
X412848Y119401D01*
G01X418723Y116977D02*
X412370Y118247D01*
G01X429627Y118202D02*
X418845D01*
G01X430135Y116977D02*
X418723D01*
G01X400161Y119620D02*
X379226Y151062D01*
G01X401045Y120503D02*
X380376Y151546D01*
G01X408118Y114314D02*
X400161Y119620D01*
G01X408600Y115466D02*
X401045Y120503D01*
G01X417337Y112400D02*
X408118Y114314D01*
G01X417463Y113625D02*
X408600Y115466D01*
G01X431981Y112400D02*
X417337D01*
G01X431473Y113625D02*
X417463D01*
G01X401045Y120503D02*
X380376Y151546D01*
G01X400161Y119620D02*
X379226Y151062D01*
G01X408600Y115466D02*
X401045Y120503D01*
G01X408118Y114314D02*
X400161Y119620D01*
G01X417463Y113625D02*
X408600Y115466D01*
G01X417337Y112400D02*
X408118Y114314D01*
G01X431473Y113625D02*
X417463D01*
G01X431981Y112400D02*
X417337D01*
G01X397478Y115316D02*
X375022Y149124D01*
G01X398363Y116199D02*
X376172Y149607D01*
G01X408585Y107900D02*
X397478Y115316D01*
G01X408957Y109125D02*
X398363Y116199D01*
G01X435276Y107900D02*
X408585D01*
G01X434768Y109125D02*
X408957D01*
G01X398363Y116199D02*
X376172Y149607D01*
G01X397478Y115316D02*
X375022Y149124D01*
G01X408957Y109125D02*
X398363Y116199D01*
G01X408585Y107900D02*
X397478Y115316D01*
G01X434768Y109125D02*
X408957D01*
G01X435276Y107900D02*
X408585D01*
G01X394433Y111399D02*
X370695Y147012D01*
G01X395317Y112282D02*
X371845Y147497D01*
G01X406411Y103400D02*
X394433Y111399D01*
G01X406783Y104625D02*
X395317Y112282D01*
G01X439133Y103400D02*
X406411D01*
G01X438625Y104625D02*
X406783D01*
G01X395317Y112282D02*
X371845Y147497D01*
G01X394433Y111399D02*
X370695Y147012D01*
G01X406783Y104625D02*
X395317Y112282D01*
G01X406411Y103400D02*
X394433Y111399D01*
G01X438625Y104625D02*
X406783D01*
G01X439133Y103400D02*
X406411D01*
G01X391218Y107122D02*
X366432Y144583D01*
G01X392104Y108005D02*
X367583Y145065D01*
G01X403698Y98800D02*
X391218Y107122D01*
G01X404070Y100025D02*
X392104Y108005D01*
G01X443401Y98800D02*
X403698D01*
G01X442893Y100025D02*
X404070D01*
G01X392104Y108005D02*
X367583Y145065D01*
G01X391218Y107122D02*
X366432Y144583D01*
G01X404070Y100025D02*
X392104Y108005D01*
G01X403698Y98800D02*
X391218Y107122D01*
G01X442893Y100025D02*
X404070D01*
G01X443401Y98800D02*
X403698D01*
G01X386996Y104057D02*
X357107Y150061D01*
G01X387886Y104938D02*
X358258Y150538D01*
G01X401824Y94200D02*
X386996Y104057D01*
G01X402195Y95425D02*
X387886Y104938D01*
G01X445301Y94200D02*
X401824D01*
G01X444793Y95425D02*
X402195D01*
G01X387886Y104938D02*
X358258Y150538D01*
G01X386996Y104057D02*
X357107Y150061D01*
G01X402195Y95425D02*
X387886Y104938D01*
G01X401824Y94200D02*
X386996Y104057D01*
G01X444793Y95425D02*
X402195D01*
G01X445301Y94200D02*
X401824D01*
G01X371983Y115222D02*
X359662Y123221D01*
G01X371097Y114336D02*
X358776Y122335D01*
G01X380854Y101566D02*
X371983Y115222D01*
G01X379968Y100680D02*
X371097Y114336D01*
G01X383578Y99797D02*
X380854Y101566D01*
G01X398815Y88442D02*
X379968Y100680D01*
G01X387478Y97265D02*
X386031Y98204D01*
G01X398815Y88442D02*
X379968Y100680D01*
G01X391378Y94732D02*
X389931Y95672D01*
G01X398815Y88442D02*
X379968Y100680D01*
G01X395278Y92200D02*
X393831Y93139D01*
G01X398815Y88442D02*
X379968Y100680D01*
G01X399178Y89667D02*
X397731Y90606D01*
G01X398815Y88442D02*
X379968Y100680D01*
G01X426215Y89667D02*
X399178D01*
G01X446842Y88442D02*
X398815D01*
G01X446842D02*
X398815D01*
G01X446842D02*
X398815D01*
G01X446842D02*
X398815D01*
G01X446842D02*
X398815D01*
G01X371097Y114336D02*
X358776Y122335D01*
G01X371983Y115222D02*
X359662Y123221D01*
G01X379968Y100680D02*
X371097Y114336D01*
G01X380854Y101566D02*
X371983Y115222D01*
G01X398815Y88442D02*
X379968Y100680D01*
G01X383578Y99797D02*
X380854Y101566D01*
G01X387478Y97265D02*
X386031Y98204D01*
G01X391378Y94732D02*
X389931Y95672D01*
G01X395278Y92200D02*
X393831Y93139D01*
G01X399178Y89667D02*
X397731Y90606D01*
G01X446842Y88442D02*
X398815D01*
G01X426215Y89667D02*
X399178D01*
G01X403199Y173834D02*
Y157170D01*
G01X401974Y173326D02*
Y156946D01*
G01X401625Y175408D02*
X403199Y173834D01*
G01X400400Y174900D02*
X401974Y173326D01*
G01X401625Y296515D02*
Y175408D01*
G01X400400Y296007D02*
Y174900D01*
G01X401974Y173326D02*
Y156946D01*
G01X403199Y173834D02*
Y157170D01*
G01X400400Y174900D02*
X401974Y173326D01*
G01X401625Y175408D02*
X403199Y173834D01*
G01X400400Y296007D02*
Y174900D01*
G01X401625Y296515D02*
Y175408D01*
G01X390724Y202415D02*
X387423Y217952D01*
G01X389473Y202408D02*
X387049Y213815D01*
G01X390724Y202415D02*
X387423Y217952D01*
G01X386086Y185549D02*
X389473Y202408D01*
G01X387337Y185556D02*
X390724Y202415D01*
G01X392072Y157373D02*
X386086Y185549D01*
G01X393222Y157858D02*
X387337Y185556D01*
G01X405871Y136679D02*
X392072Y157373D01*
G01X406754Y137563D02*
X393222Y157858D01*
G01X410646Y134970D02*
X406754Y137563D01*
G01X390724Y202415D02*
X387423Y217952D01*
G01X389473Y202408D02*
X387049Y213815D01*
G01X387337Y185556D02*
X390724Y202415D01*
G01X386086Y185549D02*
X389473Y202408D01*
G01X393222Y157858D02*
X387337Y185556D01*
G01X392072Y157373D02*
X386086Y185549D01*
G01X406754Y137563D02*
X393222Y157858D01*
G01X405871Y136679D02*
X392072Y157373D01*
G01X410646Y134970D02*
X406754Y137563D01*
G01X384797Y202430D02*
X381316Y218810D01*
G01X386049Y202437D02*
X382571Y218801D01*
G01X381352Y185349D02*
X384797Y202430D01*
G01X382604Y185356D02*
X386049Y202437D01*
G01X387728Y155358D02*
X381352Y185349D01*
G01X388878Y155843D02*
X382604Y185356D01*
G01X386049Y202437D02*
X382571Y218801D01*
G01X384797Y202430D02*
X381316Y218810D01*
G01X382604Y185356D02*
X386049Y202437D01*
G01X381352Y185349D02*
X384797Y202430D01*
G01X388878Y155843D02*
X382604Y185356D01*
G01X387728Y155358D02*
X381352Y185349D01*
G01X380189Y202390D02*
X376387Y220277D01*
G01X381441Y202395D02*
X377640Y220277D01*
G01X376656Y185050D02*
X380189Y202390D01*
G01X377908Y185055D02*
X381441Y202395D01*
G01X383473Y152975D02*
X376656Y185050D01*
G01X384623Y153458D02*
X377908Y185055D01*
G01X381441Y202395D02*
X377640Y220277D01*
G01X380189Y202390D02*
X376387Y220277D01*
G01X377908Y185055D02*
X381441Y202395D01*
G01X376656Y185050D02*
X380189Y202390D01*
G01X384623Y153458D02*
X377908Y185055D01*
G01X383473Y152975D02*
X376656Y185050D01*
G01X375551Y202500D02*
X371403Y222013D01*
G01X376803Y202506D02*
X372656Y222013D01*
G01X372008Y185004D02*
X375551Y202500D01*
G01X373260Y185010D02*
X376803Y202506D01*
G01X379226Y151062D02*
X372008Y185004D01*
G01X380376Y151546D02*
X373260Y185010D01*
G01X376803Y202506D02*
X372656Y222013D01*
G01X375551Y202500D02*
X371403Y222013D01*
G01X373260Y185010D02*
X376803Y202506D01*
G01X372008Y185004D02*
X375551Y202500D01*
G01X380376Y151546D02*
X373260Y185010D01*
G01X379226Y151062D02*
X372008Y185004D01*
G01X369318Y197736D02*
X364905Y218413D01*
G01X370569Y197744D02*
X366158Y218414D01*
G01X367073Y186520D02*
X369318Y197736D01*
G01X368324Y186527D02*
X370569Y197744D01*
G01X375022Y149124D02*
X367073Y186520D01*
G01X376172Y149607D02*
X368324Y186527D01*
G01X370569Y197744D02*
X366158Y218414D01*
G01X369318Y197736D02*
X364905Y218413D01*
G01X368324Y186527D02*
X370569Y197744D01*
G01X367073Y186520D02*
X369318Y197736D01*
G01X376172Y149607D02*
X368324Y186527D01*
G01X375022Y149124D02*
X367073Y186520D01*
G01X361508Y198242D02*
X358316Y213259D01*
G01X362761Y198242D02*
X359569Y213259D01*
G01X360658Y194243D02*
X361508Y198242D01*
G01X361911Y194243D02*
X362761Y198242D01*
G01X370695Y147012D02*
X360658Y194243D01*
G01X371845Y147497D02*
X361911Y194243D01*
G01X362761Y198242D02*
X359569Y213259D01*
G01X361508Y198242D02*
X358316Y213259D01*
G01X361911Y194243D02*
X362761Y198242D01*
G01X360658Y194243D02*
X361508Y198242D01*
G01X371845Y147497D02*
X361911Y194243D01*
G01X370695Y147012D02*
X360658Y194243D01*
G01X388688Y229801D02*
X373902Y299358D01*
G01X389941Y229801D02*
X375053Y299835D01*
G01X386170Y217952D02*
X388688Y229801D01*
G01X387423Y217952D02*
X389941Y229801D01*
G01X387049Y213815D02*
X386170Y217952D01*
G01X389941Y229801D02*
X375053Y299835D01*
G01X388688Y229801D02*
X373902Y299358D01*
G01X387423Y217952D02*
X389941Y229801D01*
G01X386170Y217952D02*
X388688Y229801D01*
G01X387049Y213815D02*
X386170Y217952D01*
G01X383665Y229847D02*
X369483Y297764D01*
G01X384917Y229845D02*
X370636Y298239D01*
G01X381316Y218810D02*
X383665Y229847D01*
G01X382571Y218801D02*
X384917Y229845D01*
G01D02*
X370636Y298239D01*
G01X383665Y229847D02*
X369483Y297764D01*
G01X382571Y218801D02*
X384917Y229845D01*
G01X381316Y218810D02*
X383665Y229847D01*
G01X378658Y230962D02*
X365112Y295918D01*
G01X379911Y230960D02*
X366265Y296393D01*
G01X376387Y220277D02*
X378659Y230962D01*
G01X377640Y220277D02*
X379911Y230960D01*
G01D02*
X366265Y296393D01*
G01X378658Y230962D02*
X365112Y295918D01*
G01X377640Y220277D02*
X379911Y230960D01*
G01X376387Y220277D02*
X378659Y230962D01*
G01X373605Y232373D02*
X360838Y293734D01*
G01X374857Y232370D02*
X361991Y294208D01*
G01X371403Y222013D02*
X373605Y232373D01*
G01X372656Y222013D02*
X374857Y232370D01*
G01D02*
X361991Y294208D01*
G01X373605Y232373D02*
X360838Y293734D01*
G01X372656Y222013D02*
X374857Y232370D01*
G01X371403Y222013D02*
X373605Y232373D01*
G01X368309Y234425D02*
X356501Y290587D01*
G01X369562Y234424D02*
X357653Y291063D01*
G01X364905Y218413D02*
X368309Y234425D01*
G01X366158Y218414D02*
X369562Y234424D01*
G01D02*
X357653Y291063D01*
G01X368309Y234425D02*
X356501Y290587D01*
G01X366158Y218414D02*
X369562Y234424D01*
G01X364905Y218413D02*
X368309Y234425D01*
G01X358316Y213259D02*
X361495Y228223D01*
G01X359569Y213259D02*
X362748Y228222D01*
G01X359569Y213259D02*
X362748Y228222D01*
G01X358316Y213259D02*
X361495Y228223D01*
G01X371300Y326840D02*
X401625Y296515D01*
G01X370075Y326332D02*
X400400Y296007D01*
G01X371300Y343500D02*
Y326840D01*
G01X370075Y344008D02*
Y326332D01*
G01X391113Y363313D02*
X371300Y343500D01*
G01X389888Y363821D02*
X370075Y344008D01*
G01Y326332D02*
X400400Y296007D01*
G01X371300Y326840D02*
X401625Y296515D01*
G01X370075Y344008D02*
Y326332D01*
G01X371300Y343500D02*
Y326840D01*
G01X389888Y363821D02*
X370075Y344008D01*
G01X391113Y363313D02*
X371300Y343500D01*
G01X391113Y469987D02*
Y363313D01*
G01X389888Y469479D02*
Y363821D01*
G01Y469479D02*
Y363821D01*
G01X391113Y469987D02*
Y363313D01*
G01X385900Y475200D02*
X391113Y469987D01*
G01X384675Y474692D02*
X389888Y469479D01*
G01X385900Y493339D02*
Y475200D01*
G01X384675Y493847D02*
Y474692D01*
G01X388763Y496202D02*
X385900Y493339D01*
G01X387538Y496710D02*
X384675Y493847D01*
G01Y474692D02*
X389888Y469479D01*
G01X385900Y475200D02*
X391113Y469987D01*
G01X384675Y493847D02*
Y474692D01*
G01X385900Y493339D02*
Y475200D01*
G01X387538Y496710D02*
X384675Y493847D01*
G01X388763Y496202D02*
X385900Y493339D01*
G01X388763Y501356D02*
Y496202D01*
G01X387538Y501864D02*
Y496710D01*
G01X391141Y503734D02*
X388763Y501356D01*
G01X389916Y504242D02*
X387538Y501864D01*
G01X391141Y579880D02*
Y503734D01*
G01X389916Y580388D02*
Y504242D01*
G01X387538Y501864D02*
Y496710D01*
G01X388763Y501356D02*
Y496202D01*
G01X389916Y504242D02*
X387538Y501864D01*
G01X391141Y503734D02*
X388763Y501356D01*
G01X389916Y580388D02*
Y504242D01*
G01X391141Y579880D02*
Y503734D01*
G01X392912Y581651D02*
X391141Y579880D01*
G01X391687Y582159D02*
X389916Y580388D01*
G01X392912Y610482D02*
Y581651D01*
G01X391687Y609974D02*
Y582159D01*
G01X391686Y610989D02*
Y609975D01*
G01X394198Y611768D02*
X392912Y610482D01*
G01X392973Y612276D02*
X391686Y610989D01*
G01X394198Y644184D02*
Y611768D01*
G01X392973Y643676D02*
Y612276D01*
G01X391687Y582159D02*
X389916Y580388D01*
G01X392912Y581651D02*
X391141Y579880D01*
G01X391687Y609974D02*
Y582159D01*
G01X392912Y610482D02*
Y581651D01*
G01X391686Y610989D02*
Y609975D01*
G01X392912Y610482D02*
Y581651D01*
G01X392973Y612276D02*
X391686Y610989D01*
G01X394198Y611768D02*
X392912Y610482D01*
G01X392973Y643676D02*
Y612276D01*
G01X394198Y644184D02*
Y611768D01*
G01X392607Y645775D02*
X394198Y644184D01*
G01X392099Y644550D02*
X392973Y643676D01*
G01X389712Y645775D02*
X392607D01*
G01X389288Y644550D02*
X392099D01*
G01D02*
X392973Y643676D01*
G01X392607Y645775D02*
X394198Y644184D01*
G01X389288Y644550D02*
X392099D01*
G01X389712Y645775D02*
X392607D01*
G01X432896Y119738D02*
X430135Y116977D01*
G01X431671Y120246D02*
X429627Y118202D01*
G01X432896Y131969D02*
Y119738D01*
G01X431671Y131969D02*
Y120246D01*
G01X433780Y132853D02*
G03X432896Y131969I0J-884D01*
G01X433780Y134078D02*
G03X431671Y131969I0J-2109D01*
G01X435183Y132853D02*
X433780D01*
G01X435184Y134078D02*
X433780D01*
G01X431671Y120246D02*
X429627Y118202D01*
G01X432896Y119738D02*
X430135Y116977D01*
G01X431671Y131969D02*
Y120246D01*
G01X432896Y131969D02*
Y119738D01*
G01X433780Y134078D02*
G03X431671Y131969I0J-2109D01*
G01X433780Y132853D02*
G03X432896Y131969I0J-884D01*
G01X435184Y134078D02*
X433780D01*
G01X435183Y132853D02*
X433780D01*
G01X439983Y120402D02*
X431981Y112400D01*
G01X438758Y120910D02*
X431473Y113625D01*
G01X439983Y127274D02*
Y120402D01*
G01X438758Y127274D02*
Y120910D01*
G01X440837Y128128D02*
G03X439983Y127274I0J-854D01*
G01X440837Y129353D02*
G03X438758Y127274I0J-2079D01*
G01X442270Y128128D02*
X440837D01*
G01X442270Y129353D02*
X440837D01*
G01X438758Y120910D02*
X431473Y113625D01*
G01X439983Y120402D02*
X431981Y112400D01*
G01X438758Y127274D02*
Y120910D01*
G01X439983Y127274D02*
Y120402D01*
G01X440837Y129353D02*
G03X438758Y127274I0J-2079D01*
G01X440837Y128128D02*
G03X439983Y127274I0J-854D01*
G01X442270Y129353D02*
X440837D01*
G01X442270Y128128D02*
X440837D01*
G01X447069Y119693D02*
X435276Y107900D01*
G01X445844Y120201D02*
X434768Y109125D01*
G01X447069Y131969D02*
Y119693D01*
G01X445844Y131969D02*
Y120201D01*
G01X447953Y132853D02*
G03X447069Y131969I0J-884D01*
G01X447953Y134078D02*
G03X445844Y131969I0J-2109D01*
G01X449356Y132853D02*
X447953D01*
G01X449357Y134078D02*
X447953D01*
G01X445844Y120201D02*
X434768Y109125D01*
G01X447069Y119693D02*
X435276Y107900D01*
G01X445844Y131969D02*
Y120201D01*
G01X447069Y131969D02*
Y119693D01*
G01X447953Y134078D02*
G03X445844Y131969I0J-2109D01*
G01X447953Y132853D02*
G03X447069Y131969I0J-884D01*
G01X449357Y134078D02*
X447953D01*
G01X449356Y132853D02*
X447953D01*
G01X454156Y118423D02*
X439133Y103400D01*
G01X452931Y118931D02*
X438625Y104625D01*
G01X454156Y127274D02*
Y118423D01*
G01X452931Y127274D02*
Y118931D01*
G01X455010Y128128D02*
G03X454156Y127274I0J-854D01*
G01X455010Y129353D02*
G03X452931Y127274I0J-2079D01*
G01X456443Y128128D02*
X455010D01*
G01X456443Y129353D02*
X455010D01*
G01X452931Y118931D02*
X438625Y104625D01*
G01X454156Y118423D02*
X439133Y103400D01*
G01X452931Y127274D02*
Y118931D01*
G01X454156Y127274D02*
Y118423D01*
G01X455010Y129353D02*
G03X452931Y127274I0J-2079D01*
G01X455010Y128128D02*
G03X454156Y127274I0J-854D01*
G01X456443Y129353D02*
X455010D01*
G01X456443Y128128D02*
X455010D01*
G01X456001Y111400D02*
X443401Y98800D01*
G01X455493Y112625D02*
X442893Y100025D01*
G01X457601Y111400D02*
X456001D01*
G01X457093Y112625D02*
X455493D01*
G01X461242Y115041D02*
X457601Y111400D01*
G01X460017Y115549D02*
X457093Y112625D01*
G01X461242Y131969D02*
Y115041D01*
G01X460017Y131969D02*
Y115549D01*
G01X462126Y132853D02*
G03X461242Y131969I0J-884D01*
G01X462126Y134078D02*
G03X460017Y131969I0J-2109D01*
G01X463529Y132853D02*
X462126D01*
G01X463530Y134078D02*
X462126D01*
G01X455493Y112625D02*
X442893Y100025D01*
G01X456001Y111400D02*
X443401Y98800D01*
G01X457093Y112625D02*
X455493D01*
G01X457601Y111400D02*
X456001D01*
G01X460017Y115549D02*
X457093Y112625D01*
G01X461242Y115041D02*
X457601Y111400D01*
G01X460017Y131969D02*
Y115549D01*
G01X461242Y131969D02*
Y115041D01*
G01X462126Y134078D02*
G03X460017Y131969I0J-2109D01*
G01X462126Y132853D02*
G03X461242Y131969I0J-884D01*
G01X463530Y134078D02*
X462126D01*
G01X463529Y132853D02*
X462126D01*
G01X457501Y106400D02*
X445301Y94200D01*
G01X456993Y107625D02*
X444793Y95425D01*
G01X459100Y106400D02*
X457501D01*
G01X458592Y107625D02*
X456993D01*
G01X468329Y115629D02*
X459100Y106400D01*
G01X467104Y116137D02*
X458592Y107625D01*
G01X468329Y127273D02*
Y115629D01*
G01X467104Y127273D02*
Y116137D01*
G01X469184Y128128D02*
G03X468329Y127273I0J-855D01*
G01X469184Y129353D02*
G03X467104Y127273I0J-2080D01*
G01X470617Y128128D02*
X469184D01*
G01X470617Y129353D02*
X469184D01*
G01X456993Y107625D02*
X444793Y95425D01*
G01X457501Y106400D02*
X445301Y94200D01*
G01X458592Y107625D02*
X456993D01*
G01X459100Y106400D02*
X457501D01*
G01X467104Y116137D02*
X458592Y107625D01*
G01X468329Y115629D02*
X459100Y106400D01*
G01X467104Y127273D02*
Y116137D01*
G01X468329Y127273D02*
Y115629D01*
G01X469184Y129353D02*
G03X467104Y127273I0J-2080D01*
G01X469184Y128128D02*
G03X468329Y127273I0J-855D01*
G01X470617Y129353D02*
X469184D01*
G01X470617Y128128D02*
X469184D01*
G01X430865Y89667D02*
X429140D01*
G01X435515D02*
X433790D01*
G01X440165D02*
X438440D01*
G01X446334D02*
X443090D01*
G01X459192Y102525D02*
X446334Y89667D01*
G01X459700Y101300D02*
X446842Y88442D01*
G01X463192Y102525D02*
X459192D01*
G01X463700Y101300D02*
X459700D01*
G01X475275Y114608D02*
X463192Y102525D01*
G01X476500Y114100D02*
X463700Y101300D01*
G01X475275Y169273D02*
Y114608D01*
G01X476500Y169273D02*
Y114100D01*
G01X430865Y89667D02*
X429140D01*
G01X435515D02*
X433790D01*
G01X440165D02*
X438440D01*
G01X446334D02*
X443090D01*
G01X459700Y101300D02*
X446842Y88442D01*
G01X459192Y102525D02*
X446334Y89667D01*
G01X463700Y101300D02*
X459700D01*
G01X463192Y102525D02*
X459192D01*
G01X476500Y114100D02*
X463700Y101300D01*
G01X475275Y114608D02*
X463192Y102525D01*
G01X476500Y169273D02*
Y114100D01*
G01X475275Y169273D02*
Y114608D01*
G01X473900Y170648D02*
G02X475275Y169273I0J-1375D01*
G01X473900Y171873D02*
G02X476500Y169273I0J-2600D01*
G01X471904Y170648D02*
X473900D01*
G01X471903Y171873D02*
X473900D01*
G01D02*
G02X476500Y169273I0J-2600D01*
G01X473900Y170648D02*
G02X475275Y169273I0J-1375D01*
G01X471903Y171873D02*
X473900D01*
G01X471904Y170648D02*
X473900D01*
G01X547165Y132853D02*
X548568D01*
G01X547165Y134078D02*
X548569D01*
G01X546281Y131969D02*
G02X547165Y132853I884J0D01*
G01X545056Y131969D02*
G02X547165Y134078I2109J0D01*
G01X546281Y119519D02*
Y131969D01*
G01X545056Y119011D02*
Y131969D01*
G01X551500Y114300D02*
X546281Y119519D01*
G01X550992Y113075D02*
X545056Y119011D01*
G01X558302Y114300D02*
X551500D01*
G01X558423Y113075D02*
X550992D01*
G01X559274Y113244D02*
X558423Y113075D01*
G01X561233Y114885D02*
X558302Y114300D01*
G01X559274Y113244D02*
X558423Y113075D01*
G01X559517Y113292D02*
X559274Y113244D01*
G01X560927Y113573D02*
X559517Y113292D01*
G01X561704Y113729D02*
X560927Y113573D01*
G01X563650Y116455D02*
X561233Y114885D01*
G01X564536Y115569D02*
X561704Y113729D01*
G01X586551Y151722D02*
X563650Y116455D01*
G01X587703Y151246D02*
X564536Y115569D01*
G01X547165Y134078D02*
X548569D01*
G01X547165Y132853D02*
X548568D01*
G01X545056Y131969D02*
G02X547165Y134078I2109J0D01*
G01X546281Y131969D02*
G02X547165Y132853I884J0D01*
G01X545056Y119011D02*
Y131969D01*
G01X546281Y119519D02*
Y131969D01*
G01X550992Y113075D02*
X545056Y119011D01*
G01X551500Y114300D02*
X546281Y119519D01*
G01X558423Y113075D02*
X550992D01*
G01X558302Y114300D02*
X551500D01*
G01X559274Y113244D02*
X558423Y113075D01*
G01X558302Y114300D02*
X551500D01*
G01X561233Y114885D02*
X558302Y114300D01*
G01X559517Y113292D02*
X559274Y113244D01*
G01X561233Y114885D02*
X558302Y114300D01*
G01X560927Y113573D02*
X559517Y113292D01*
G01X561233Y114885D02*
X558302Y114300D01*
G01X561704Y113729D02*
X560927Y113573D01*
G01X561233Y114885D02*
X558302Y114300D01*
G01X564536Y115569D02*
X561704Y113729D01*
G01X563650Y116455D02*
X561233Y114885D01*
G01X587703Y151246D02*
X564536Y115569D01*
G01X586551Y151722D02*
X563650Y116455D01*
G01X554223Y128128D02*
X555656D01*
G01X554223Y129353D02*
X555656D01*
G01X553368Y127273D02*
G02X554223Y128128I855J0D01*
G01X552143Y127273D02*
G02X554223Y129353I2080J0D01*
G01X553368Y119738D02*
Y127273D01*
G01X552143Y119230D02*
Y127273D01*
G01X554306Y118800D02*
X553368Y119738D01*
G01X553798Y117575D02*
X552143Y119230D01*
G01X556489Y118800D02*
X554306D01*
G01X556610Y117575D02*
X553798D01*
G01X559695Y119439D02*
X556489Y118800D01*
G01X560442Y118338D02*
X556610Y117575D01*
G01X580510Y151499D02*
X559695Y119439D01*
G01X581662Y151022D02*
X560442Y118338D01*
G01X554223Y129353D02*
X555656D01*
G01X554223Y128128D02*
X555656D01*
G01X552143Y127273D02*
G02X554223Y129353I2080J0D01*
G01X553368Y127273D02*
G02X554223Y128128I855J0D01*
G01X552143Y119230D02*
Y127273D01*
G01X553368Y119738D02*
Y127273D01*
G01X553798Y117575D02*
X552143Y119230D01*
G01X554306Y118800D02*
X553368Y119738D01*
G01X556610Y117575D02*
X553798D01*
G01X556489Y118800D02*
X554306D01*
G01X560442Y118338D02*
X556610Y117575D01*
G01X559695Y119439D02*
X556489Y118800D01*
G01X581662Y151022D02*
X560442Y118338D01*
G01X580510Y151499D02*
X559695Y119439D01*
G01X504646Y132853D02*
X506049D01*
G01X504646Y134078D02*
X506050D01*
G01X503686Y131893D02*
G02X504646Y132853I960J0D01*
G01X502461Y131893D02*
G02X504646Y134078I2185J0D01*
G01X503686Y117509D02*
Y131893D01*
G01X502461Y117001D02*
Y131893D01*
G01X535856Y85339D02*
X503686Y117509D01*
G01X535348Y84114D02*
X502461Y117001D01*
G01X571490Y85339D02*
X535856D01*
G01X571612Y84114D02*
X535348D01*
G01X504646Y134078D02*
X506050D01*
G01X504646Y132853D02*
X506049D01*
G01X502461Y131893D02*
G02X504646Y134078I2185J0D01*
G01X503686Y131893D02*
G02X504646Y132853I960J0D01*
G01X502461Y117001D02*
Y131893D01*
G01X503686Y117509D02*
Y131893D01*
G01X535348Y84114D02*
X502461Y117001D01*
G01X535856Y85339D02*
X503686Y117509D01*
G01X571612Y84114D02*
X535348D01*
G01X571490Y85339D02*
X535856D01*
G01X511703Y128128D02*
X513136D01*
G01X511703Y129353D02*
X513136D01*
G01X510849Y127274D02*
G02X511703Y128128I854J0D01*
G01X509624Y127274D02*
G02X511703Y129353I2079J0D01*
G01X510849Y116751D02*
Y127274D01*
G01X509624Y116243D02*
Y127274D01*
G01X536761Y90839D02*
X510849Y116751D01*
G01X536253Y89614D02*
X509624Y116243D01*
G01X568694Y90839D02*
X536761D01*
G01X568816Y89614D02*
X536253D01*
G01X572406Y91581D02*
X568694Y90839D01*
G01X576595Y91168D02*
X568816Y89614D01*
G01X576595Y91168D02*
X568816Y89614D01*
G01X576595Y91168D02*
X568816Y89614D01*
G01X511703Y129353D02*
X513136D01*
G01X511703Y128128D02*
X513136D01*
G01X509624Y127274D02*
G02X511703Y129353I2079J0D01*
G01X510849Y127274D02*
G02X511703Y128128I854J0D01*
G01X509624Y116243D02*
Y127274D01*
G01X510849Y116751D02*
Y127274D01*
G01X536253Y89614D02*
X509624Y116243D01*
G01X536761Y90839D02*
X510849Y116751D01*
G01X568816Y89614D02*
X536253D01*
G01X568694Y90839D02*
X536761D01*
G01X576595Y91168D02*
X568816Y89614D01*
G01X572406Y91581D02*
X568694Y90839D01*
G01X518819Y132853D02*
X520222D01*
G01X518819Y134078D02*
X520223D01*
G01X517935Y131969D02*
G02X518819Y132853I884J0D01*
G01X516710Y131969D02*
G02X518819Y134078I2109J0D01*
G01X517935Y116165D02*
Y131969D01*
G01X516710Y115657D02*
Y131969D01*
G01X538711Y95389D02*
X517935Y116165D01*
G01X538203Y94164D02*
X516710Y115657D01*
G01X560580Y95389D02*
X538711D01*
G01X560702Y94164D02*
X538203D01*
G01X572895Y97851D02*
X560580Y95389D01*
G01X573373Y96697D02*
X560702Y94164D01*
G01X518819Y134078D02*
X520223D01*
G01X518819Y132853D02*
X520222D01*
G01X516710Y131969D02*
G02X518819Y134078I2109J0D01*
G01X517935Y131969D02*
G02X518819Y132853I884J0D01*
G01X516710Y115657D02*
Y131969D01*
G01X517935Y116165D02*
Y131969D01*
G01X538203Y94164D02*
X516710Y115657D01*
G01X538711Y95389D02*
X517935Y116165D01*
G01X560702Y94164D02*
X538203D01*
G01X560580Y95389D02*
X538711D01*
G01X573373Y96697D02*
X560702Y94164D01*
G01X572895Y97851D02*
X560580Y95389D01*
G01X525877Y128128D02*
X527310D01*
G01X525877Y129353D02*
X527310D01*
G01X525022Y127273D02*
G02X525877Y128128I855J0D01*
G01X523797Y127273D02*
G02X525877Y129353I2080J0D01*
G01X525022Y116038D02*
Y127273D01*
G01X523797Y115530D02*
Y127273D01*
G01X541122Y99938D02*
X525022Y116038D01*
G01X540614Y98713D02*
X523797Y115530D01*
G01X560258Y99938D02*
X541122D01*
G01X560380Y98713D02*
X540614D01*
G01X569324Y101750D02*
X560258Y99938D01*
G01X569802Y100596D02*
X560380Y98713D01*
G01X577676Y107319D02*
X569324Y101750D01*
G01X578560Y106435D02*
X569802Y100596D01*
G01X525877Y129353D02*
X527310D01*
G01X525877Y128128D02*
X527310D01*
G01X523797Y127273D02*
G02X525877Y129353I2080J0D01*
G01X525022Y127273D02*
G02X525877Y128128I855J0D01*
G01X523797Y115530D02*
Y127273D01*
G01X525022Y116038D02*
Y127273D01*
G01X540614Y98713D02*
X523797Y115530D01*
G01X541122Y99938D02*
X525022Y116038D01*
G01X560380Y98713D02*
X540614D01*
G01X560258Y99938D02*
X541122D01*
G01X569802Y100596D02*
X560380Y98713D01*
G01X569324Y101750D02*
X560258Y99938D01*
G01X578560Y106435D02*
X569802Y100596D01*
G01X577676Y107319D02*
X569324Y101750D01*
G01X532992Y132853D02*
X534395D01*
G01X532992Y134078D02*
X534396D01*
G01X532109Y131970D02*
G02X532992Y132853I883J0D01*
G01X530884Y131970D02*
G02X532992Y134078I2108J0D01*
G01X532109Y116162D02*
Y131970D01*
G01X530884Y115654D02*
Y131970D01*
G01X543833Y104438D02*
X532109Y116162D01*
G01X543325Y103213D02*
X530884Y115654D01*
G01X559235Y104438D02*
X543833D01*
G01X559357Y103213D02*
X543325D01*
G01X560906Y104773D02*
X559235Y104438D01*
G01X562820Y103906D02*
X559357Y103213D01*
G01X561743Y104941D02*
X560906Y104773D01*
G01X562820Y103906D02*
X559357Y103213D01*
G01X565924Y105779D02*
X561743Y104941D01*
G01X566164Y104577D02*
X562820Y103906D01*
G01X566402Y104625D02*
X566164Y104577D01*
G01X573648Y110929D02*
X565924Y105779D01*
G01X574532Y110045D02*
X566402Y104625D01*
G01X532992Y134078D02*
X534396D01*
G01X532992Y132853D02*
X534395D01*
G01X530884Y131970D02*
G02X532992Y134078I2108J0D01*
G01X532109Y131970D02*
G02X532992Y132853I883J0D01*
G01X530884Y115654D02*
Y131970D01*
G01X532109Y116162D02*
Y131970D01*
G01X543325Y103213D02*
X530884Y115654D01*
G01X543833Y104438D02*
X532109Y116162D01*
G01X559357Y103213D02*
X543325D01*
G01X559235Y104438D02*
X543833D01*
G01X562820Y103906D02*
X559357Y103213D01*
G01X560906Y104773D02*
X559235Y104438D01*
G01X561743Y104941D02*
X560906Y104773D01*
G01X566164Y104577D02*
X562820Y103906D01*
G01X565924Y105779D02*
X561743Y104941D01*
G01X566402Y104625D02*
X566164Y104577D01*
G01X565924Y105779D02*
X561743Y104941D01*
G01X574532Y110045D02*
X566402Y104625D01*
G01X573648Y110929D02*
X565924Y105779D01*
G01X540050Y128128D02*
X541483D01*
G01X540050Y129353D02*
X541483D01*
G01X539195Y127273D02*
G02X540050Y128128I855J0D01*
G01X537970Y127273D02*
G02X540050Y129353I2080J0D01*
G01X539195Y117838D02*
Y127273D01*
G01X537970Y117330D02*
Y127273D01*
G01X547333Y109700D02*
X539195Y117838D01*
G01X546825Y108475D02*
X537970Y117330D01*
G01X558634Y109700D02*
X547333D01*
G01X558756Y108475D02*
X546825D01*
G01X561511Y110278D02*
X558634Y109700D01*
G01X564865Y109699D02*
X558756Y108475D01*
G01X564387Y110853D02*
X561511Y110278D01*
G01X564865Y109699D02*
X558756Y108475D01*
G01X568104Y113331D02*
X564387Y110853D01*
G01X568988Y112447D02*
X564865Y109699D01*
G01X594547Y152988D02*
X568104Y113331D01*
G01X595701Y152510D02*
X568988Y112447D01*
G01X540050Y129353D02*
X541483D01*
G01X540050Y128128D02*
X541483D01*
G01X537970Y127273D02*
G02X540050Y129353I2080J0D01*
G01X539195Y127273D02*
G02X540050Y128128I855J0D01*
G01X537970Y117330D02*
Y127273D01*
G01X539195Y117838D02*
Y127273D01*
G01X546825Y108475D02*
X537970Y117330D01*
G01X547333Y109700D02*
X539195Y117838D01*
G01X558756Y108475D02*
X546825D01*
G01X558634Y109700D02*
X547333D01*
G01X564865Y109699D02*
X558756Y108475D01*
G01X561511Y110278D02*
X558634Y109700D01*
G01X564387Y110853D02*
X561511Y110278D01*
G01X568988Y112447D02*
X564865Y109699D01*
G01X568104Y113331D02*
X564387Y110853D01*
G01X595701Y152510D02*
X568988Y112447D01*
G01X594547Y152988D02*
X568104Y113331D01*
G01X577675Y86576D02*
X571490Y85339D01*
G01X578154Y85422D02*
X571612Y84114D01*
G01X592182Y96273D02*
X577675Y86576D01*
G01X585608Y90405D02*
X578154Y85422D01*
G01X593063Y95388D02*
X585608Y90405D01*
G01X626649Y147370D02*
X592182Y96273D01*
G01X627803Y146888D02*
X593063Y95388D01*
G01X578154Y85422D02*
X571612Y84114D01*
G01X577675Y86576D02*
X571490Y85339D01*
G01X585608Y90405D02*
X578154Y85422D01*
G01X592182Y96273D02*
X577675Y86576D01*
G01X593063Y95388D02*
X585608Y90405D01*
G01X592182Y96273D02*
X577675Y86576D01*
G01X627803Y146888D02*
X593063Y95388D01*
G01X626649Y147370D02*
X592182Y96273D01*
G01X575389Y92177D02*
X572406Y91581D01*
G01X576115Y92322D02*
X575389Y92177D01*
G01X588816Y99380D02*
X576595Y91168D01*
G01X587934Y100264D02*
X576115Y92322D01*
G01X588816Y99380D02*
X576595Y91168D01*
G01X620494Y148533D02*
X587934Y100264D01*
G01X621648Y148051D02*
X588816Y99380D01*
G01X575389Y92177D02*
X572406Y91581D01*
G01X576115Y92322D02*
X575389Y92177D01*
G01X588816Y99380D02*
X576595Y91168D01*
G01X576115Y92322D02*
X575389Y92177D01*
G01X587934Y100264D02*
X576115Y92322D01*
G01X621648Y148051D02*
X588816Y99380D01*
G01X620494Y148533D02*
X587934Y100264D01*
G01X581866Y103842D02*
X572895Y97851D01*
G01X582747Y102957D02*
X573373Y96697D01*
G01X613988Y151468D02*
X581866Y103842D01*
G01X615142Y150986D02*
X582747Y102957D01*
G01D02*
X573373Y96697D01*
G01X581866Y103842D02*
X572895Y97851D01*
G01X615142Y150986D02*
X582747Y102957D01*
G01X613988Y151468D02*
X581866Y103842D01*
G01X607660Y152296D02*
X577676Y107319D01*
G01X608814Y151818D02*
X578560Y106435D01*
G01X608814Y151818D02*
X578560Y106435D01*
G01X607660Y152296D02*
X577676Y107319D01*
G01X601417Y152588D02*
X573648Y110929D01*
G01X602571Y152110D02*
X574532Y110045D01*
G01X602571Y152110D02*
X574532Y110045D01*
G01X601417Y152588D02*
X573648Y110929D01*
G01X589177Y164173D02*
X586551Y151722D01*
G01X590376Y163921D02*
X587703Y151246D01*
G01X590136Y168723D02*
X589780Y167035D01*
G01X637583Y387757D02*
X590376Y163921D01*
G01X591096Y173273D02*
X590740Y171585D01*
G01X637583Y387757D02*
X590376Y163921D01*
G01X592055Y177823D02*
X591699Y176135D01*
G01X637583Y387757D02*
X590376Y163921D01*
G01X636333Y387767D02*
X592659Y180685D01*
G01X637583Y387757D02*
X590376Y163921D01*
G01D02*
X587703Y151246D01*
G01X589177Y164173D02*
X586551Y151722D01*
G01X637583Y387757D02*
X590376Y163921D01*
G01X590136Y168723D02*
X589780Y167035D01*
G01X591096Y173273D02*
X590740Y171585D01*
G01X592055Y177823D02*
X591699Y176135D01*
G01X636333Y387767D02*
X592659Y180685D01*
G01X584510Y170412D02*
X580510Y151499D01*
G01X589200Y186668D02*
X581662Y151022D01*
G01X585472Y174961D02*
X585115Y173273D01*
G01X589200Y186668D02*
X581662Y151022D01*
G01X586434Y179511D02*
X586077Y177823D01*
G01X589200Y186668D02*
X581662Y151022D01*
G01X587396Y184060D02*
X587039Y182372D01*
G01X589200Y186668D02*
X581662Y151022D01*
G01X609217Y287248D02*
X588001Y186922D01*
G01X631684Y387566D02*
X589200Y186669D01*
G01X631684Y387566D02*
X589200Y186669D01*
G01Y186668D02*
X581662Y151022D01*
G01X584510Y170412D02*
X580510Y151499D01*
G01X585472Y174961D02*
X585115Y173273D01*
G01X586434Y179511D02*
X586077Y177823D01*
G01X587396Y184060D02*
X587039Y182372D01*
G01X631684Y387566D02*
X589200Y186669D01*
G01X609217Y287248D02*
X588001Y186922D01*
G01X627393Y151091D02*
X626649Y147370D01*
G01X628595Y150851D02*
X627803Y146888D01*
G01X628305Y155651D02*
X627966Y153959D01*
G01X631805Y166900D02*
X628595Y150850D01*
G01X629217Y160210D02*
X628878Y158519D01*
G01X631805Y166900D02*
X628595Y150850D01*
G01X630128Y164770D02*
X629790Y163079D01*
G01X631805Y166900D02*
X628595Y150850D01*
G01X672430Y376290D02*
X630702Y167638D01*
G01X673680Y376289D02*
X631804Y166900D01*
G01X628595Y150851D02*
X627803Y146888D01*
G01X627393Y151091D02*
X626649Y147370D01*
G01X631805Y166900D02*
X628595Y150850D01*
G01X628305Y155651D02*
X627966Y153959D01*
G01X629217Y160210D02*
X628878Y158519D01*
G01X630128Y164770D02*
X629790Y163079D01*
G01X673680Y376289D02*
X631804Y166900D01*
G01X672430Y376290D02*
X630702Y167638D01*
G01X621358Y152853D02*
X620494Y148533D01*
G01X622560Y152612D02*
X621648Y148051D01*
G01X622270Y157413D02*
X621931Y155721D01*
G01X625770Y168662D02*
X622560Y152612D01*
G01X623182Y161973D02*
X622843Y160281D01*
G01X625770Y168662D02*
X622560Y152612D01*
G01X624093Y166532D02*
X623755Y164841D01*
G01X625770Y168662D02*
X622560Y152612D01*
G01X666300Y377581D02*
X624666Y169400D01*
G01X667550Y377581D02*
X625769Y168662D01*
G01X622560Y152612D02*
X621648Y148051D01*
G01X621358Y152853D02*
X620494Y148533D01*
G01X625770Y168662D02*
X622560Y152612D01*
G01X622270Y157413D02*
X621931Y155721D01*
G01X623182Y161973D02*
X622843Y160281D01*
G01X624093Y166532D02*
X623755Y164841D01*
G01X667550Y377581D02*
X625769Y168662D01*
G01X666300Y377581D02*
X624666Y169400D01*
G01X614914Y156099D02*
X613988Y151468D01*
G01X616116Y155860D02*
X615142Y150986D01*
G01X615826Y160658D02*
X615487Y158967D01*
G01X619425Y172405D02*
X616116Y155860D01*
G01X616738Y165218D02*
X616399Y163527D01*
G01X619425Y172405D02*
X616116Y155860D01*
G01X617650Y169778D02*
X617311Y168086D01*
G01X619425Y172405D02*
X616116Y155860D01*
G01X660163Y382333D02*
X618223Y172646D01*
G01X661413Y382333D02*
X619425Y172406D01*
G01X616116Y155860D02*
X615142Y150986D01*
G01X614914Y156099D02*
X613988Y151468D01*
G01X619425Y172405D02*
X616116Y155860D01*
G01X615826Y160658D02*
X615487Y158967D01*
G01X616738Y165218D02*
X616399Y163527D01*
G01X617650Y169778D02*
X617311Y168086D01*
G01X661413Y382333D02*
X619425Y172406D01*
G01X660163Y382333D02*
X618223Y172646D01*
G01X608975Y158870D02*
X607660Y152296D01*
G01X655414Y384816D02*
X608814Y151818D01*
G01X609887Y163430D02*
X609549Y161738D01*
G01X655414Y384816D02*
X608814Y151818D01*
G01X610799Y167990D02*
X610460Y166298D01*
G01X655414Y384816D02*
X608814Y151818D01*
G01X611711Y172549D02*
X611372Y170858D01*
G01X655414Y384816D02*
X608814Y151818D01*
G01X654164Y384817D02*
X612284Y175418D01*
G01X655414Y384816D02*
X608814Y151818D01*
G01X655414Y384816D02*
X608814Y151818D01*
G01X608975Y158870D02*
X607660Y152296D01*
G01X609887Y163430D02*
X609549Y161738D01*
G01X610799Y167990D02*
X610460Y166298D01*
G01X611711Y172549D02*
X611372Y170858D01*
G01X654164Y384817D02*
X612284Y175418D01*
G01X602400Y157504D02*
X601417Y152588D01*
G01X649225Y385373D02*
X602571Y152110D01*
G01X603312Y162064D02*
X602974Y160372D01*
G01X649225Y385373D02*
X602571Y152110D01*
G01X604224Y166623D02*
X603886Y164932D01*
G01X649225Y385373D02*
X602571Y152110D01*
G01X605136Y171183D02*
X604798Y169492D01*
G01X649225Y385373D02*
X602571Y152110D01*
G01X647975Y385374D02*
X605709Y174050D01*
G01X649225Y385373D02*
X602571Y152110D01*
G01X649225Y385373D02*
X602571Y152110D01*
G01X602400Y157504D02*
X601417Y152588D01*
G01X603312Y162064D02*
X602974Y160372D01*
G01X604224Y166623D02*
X603886Y164932D01*
G01X605136Y171183D02*
X604798Y169492D01*
G01X647975Y385374D02*
X605709Y174050D01*
G01X597667Y168589D02*
X594547Y152988D01*
G01X598869Y168351D02*
X595701Y152510D01*
G01X598594Y173227D02*
X598256Y171535D01*
G01X602239Y185196D02*
X598870Y168351D01*
G01X599522Y177865D02*
X599184Y176173D01*
G01X602239Y185196D02*
X598870Y168351D01*
G01X600450Y182503D02*
X600112Y180811D01*
G01X602239Y185196D02*
X598870Y168351D01*
G01X601019Y185441D02*
X601018Y185436D01*
G01X642701Y387593D02*
X602225Y185215D01*
G01X641452Y387597D02*
X601020Y185441D01*
G01X642701Y387593D02*
X602225Y185215D01*
G01X598869Y168351D02*
X595701Y152510D01*
G01X597667Y168589D02*
X594547Y152988D01*
G01X602239Y185196D02*
X598870Y168351D01*
G01X598594Y173227D02*
X598256Y171535D01*
G01X599522Y177865D02*
X599184Y176173D01*
G01X600450Y182503D02*
X600112Y180811D01*
G01X642701Y387593D02*
X602225Y185215D01*
G01X601019Y185441D02*
X601018Y185436D01*
G01X641452Y387597D02*
X601020Y185441D01*
G01X630434Y387576D02*
X609217Y287248D01*
G01X630434Y387576D02*
X609217Y287248D01*
G01X614349Y500952D02*
X636333Y387767D01*
G01X615597Y500952D02*
X637583Y387757D01*
G01X615597Y500952D02*
X637583Y387757D01*
G01X614349Y500952D02*
X636333Y387767D01*
G01X608997Y497847D02*
X630434Y387576D01*
G01X610245Y497847D02*
X631684Y387566D01*
G01X610245Y497847D02*
X631684Y387566D01*
G01X608997Y497847D02*
X630434Y387576D01*
G01X624363Y504436D02*
X647975Y385374D01*
G01X625612Y504438D02*
X649225Y385373D01*
G01X625612Y504438D02*
X649225Y385373D01*
G01X624363Y504436D02*
X647975Y385374D01*
G01X619326Y502372D02*
X641452Y387597D01*
G01X620574Y502371D02*
X642701Y387593D01*
G01X620574Y502371D02*
X642701Y387593D01*
G01X619326Y502372D02*
X641452Y387597D01*
G01X634947Y508437D02*
X660163Y382333D01*
G01X636196Y508439D02*
X661413Y382333D01*
G01X636196Y508439D02*
X661413Y382333D01*
G01X634947Y508437D02*
X660163Y382333D01*
G01X629750Y507927D02*
X654164Y384817D01*
G01X630999Y507929D02*
X655414Y384816D01*
G01X630999Y507929D02*
X655414Y384816D01*
G01X629750Y507927D02*
X654164Y384817D01*
G01X624320Y552292D02*
X614349Y500952D01*
G01X625476Y551813D02*
X615597Y500952D01*
G01X632289Y564104D02*
X624320Y552292D01*
G01X633172Y563221D02*
X625476Y551813D01*
G01X647272Y574214D02*
X632289Y564104D01*
G01X647751Y573058D02*
X633172Y563221D01*
G01X625476Y551813D02*
X615597Y500952D01*
G01X624320Y552292D02*
X614349Y500952D01*
G01X633172Y563221D02*
X625476Y551813D01*
G01X632289Y564104D02*
X624320Y552292D01*
G01X647751Y573058D02*
X633172Y563221D01*
G01X647272Y574214D02*
X632289Y564104D01*
G01X620175Y555342D02*
X608997Y497847D01*
G01X621331Y554863D02*
X610245Y497847D01*
G01X628220Y567270D02*
X620175Y555342D01*
G01X629103Y566387D02*
X621331Y554863D01*
G01D02*
X610245Y497847D01*
G01X620175Y555342D02*
X608997Y497847D01*
G01X629103Y566387D02*
X621331Y554863D01*
G01X628220Y567270D02*
X620175Y555342D01*
G01X640075Y508731D02*
X666300Y377581D01*
G01X641325Y508734D02*
X667550Y377581D01*
G01X646183Y540151D02*
X640075Y508731D01*
G01X647339Y539672D02*
X641324Y508734D01*
G01X641325D02*
X667550Y377581D01*
G01X640075Y508731D02*
X666300Y377581D01*
G01X647339Y539672D02*
X641324Y508734D01*
G01X646183Y540151D02*
X640075Y508731D01*
G01X636678Y517234D02*
X634947Y508437D01*
G01X639564Y525555D02*
X636196Y508439D01*
G01X638361Y525792D02*
X636678Y517234D01*
G01X639564Y525555D02*
X636196Y508439D01*
G01X641717Y542852D02*
X638361Y525792D01*
G01X642872Y542372D02*
X639564Y525555D01*
G01X646422Y549826D02*
X641717Y542852D01*
G01X647305Y548943D02*
X642872Y542372D01*
G01X639564Y525555D02*
X636196Y508439D01*
G01X636678Y517234D02*
X634947Y508437D01*
G01X638361Y525792D02*
X636678Y517234D01*
G01X642872Y542372D02*
X639564Y525555D01*
G01X641717Y542852D02*
X638361Y525792D01*
G01X647305Y548943D02*
X642872Y542372D01*
G01X646422Y549826D02*
X641717Y542852D01*
G01X636878Y544610D02*
X629750Y507927D01*
G01X638034Y544131D02*
X630999Y507929D01*
G01X643141Y553897D02*
X636878Y544610D01*
G01X644024Y553014D02*
X638034Y544131D01*
G01D02*
X630999Y507929D01*
G01X636878Y544610D02*
X629750Y507927D01*
G01X644024Y553014D02*
X638034Y544131D01*
G01X643141Y553897D02*
X636878Y544610D01*
G01X632911Y548400D02*
X624363Y504436D01*
G01X634067Y547921D02*
X625612Y504438D01*
G01X639019Y557455D02*
X632911Y548400D01*
G01X639902Y556572D02*
X634067Y547921D01*
G01X650554Y565238D02*
X639019Y557455D01*
G01X651033Y564082D02*
X639902Y556572D01*
G01X634067Y547921D02*
X625612Y504438D01*
G01X632911Y548400D02*
X624363Y504436D01*
G01X639902Y556572D02*
X634067Y547921D01*
G01X639019Y557455D02*
X632911Y548400D01*
G01X651033Y564082D02*
X639902Y556572D01*
G01X650554Y565238D02*
X639019Y557455D01*
G01X628681Y550503D02*
X619326Y502372D01*
G01X629837Y550024D02*
X620574Y502371D01*
G01X635438Y560519D02*
X628681Y550503D01*
G01X636321Y559636D02*
X629837Y550024D01*
G01X648948Y569634D02*
X635438Y560519D01*
G01X649427Y568478D02*
X636321Y559636D01*
G01X629837Y550024D02*
X620574Y502371D01*
G01X628681Y550503D02*
X619326Y502372D01*
G01X636321Y559636D02*
X629837Y550024D01*
G01X635438Y560519D02*
X628681Y550503D01*
G01X649427Y568478D02*
X636321Y559636D01*
G01X648948Y569634D02*
X635438Y560519D01*
G01X645179Y578708D02*
X628220Y567270D01*
G01X645658Y577552D02*
X629103Y566387D01*
G01X645658Y577552D02*
X629103Y566387D01*
G01X645179Y578708D02*
X628220Y567270D01*
G01X645772Y510417D02*
X672430Y376290D01*
G01X647021Y510420D02*
X673680Y376289D01*
G01X647021Y510420D02*
X673680Y376289D01*
G01X645772Y510417D02*
X672430Y376290D01*
G01X651064Y537636D02*
X645772Y510417D01*
G01X652216Y537138D02*
X647021Y510420D01*
G01X656795Y545609D02*
X651064Y537636D01*
G01X657586Y544609D02*
X652216Y537138D01*
G01X664125Y548628D02*
X656795Y545609D01*
G01X664368Y547403D02*
X657586Y544609D01*
G01X668727Y548628D02*
X664125D01*
G01X668728Y547403D02*
X664368D01*
G01X671422Y547513D02*
G03X668727Y548628I-2693J-2695D01*
G01X670556Y546646D02*
G03X668728Y547403I-1828J-1828D01*
G01X672243Y546693D02*
X671422Y547513D01*
G01X671377Y545826D02*
X670556Y546646D01*
G01X672245Y546692D02*
X672243Y546694D01*
G01X671377Y545826D02*
X670556Y546646D01*
G01X652216Y537138D02*
X647021Y510420D01*
G01X651064Y537636D02*
X645772Y510417D01*
G01X657586Y544609D02*
X652216Y537138D01*
G01X656795Y545609D02*
X651064Y537636D01*
G01X664368Y547403D02*
X657586Y544609D01*
G01X664125Y548628D02*
X656795Y545609D01*
G01X668728Y547403D02*
X664368D01*
G01X668727Y548628D02*
X664125D01*
G01X670556Y546646D02*
G03X668728Y547403I-1828J-1828D01*
G01X671422Y547513D02*
G03X668727Y548628I-2693J-2695D01*
G01X671377Y545826D02*
X670556Y546646D01*
G01X672243Y546693D02*
X671422Y547513D01*
G01X672245Y546692D02*
X672243Y546694D01*
G01X651183Y547563D02*
X646183Y540151D01*
G01X652066Y546681D02*
X647339Y539672D01*
G01X657947Y552128D02*
X651183Y547563D01*
G01X658425Y550972D02*
X652066Y546681D01*
G01X679087Y556213D02*
X657947Y552128D01*
G01X679205Y554988D02*
X658425Y550972D01*
G01X683761Y556213D02*
X679087D01*
G01X683762Y554988D02*
X679205D01*
G01X686596Y555040D02*
G03X683761Y556213I-2833J-2835D01*
G01X685730Y554173D02*
G03X683762Y554988I-1968J-1968D01*
G01X687417Y554220D02*
X686596Y555040D01*
G01X686551Y553353D02*
X685730Y554173D01*
G01X687419Y554219D02*
X687417Y554221D01*
G01X686551Y553353D02*
X685730Y554173D01*
G01X652066Y546681D02*
X647339Y539672D01*
G01X651183Y547563D02*
X646183Y540151D01*
G01X658425Y550972D02*
X652066Y546681D01*
G01X657947Y552128D02*
X651183Y547563D01*
G01X679205Y554988D02*
X658425Y550972D01*
G01X679087Y556213D02*
X657947Y552128D01*
G01X683762Y554988D02*
X679205D01*
G01X683761Y556213D02*
X679087D01*
G01X685730Y554173D02*
G03X683762Y554988I-1968J-1968D01*
G01X686596Y555040D02*
G03X683761Y556213I-2833J-2835D01*
G01X686551Y553353D02*
X685730Y554173D01*
G01X687417Y554220D02*
X686596Y555040D01*
G01X687419Y554219D02*
X687417Y554221D01*
G01X651988Y553579D02*
X646422Y549826D01*
G01X658041Y556181D02*
X647305Y548943D01*
G01X654672Y555388D02*
X651988Y553579D01*
G01X658041Y556181D02*
X647305Y548943D01*
G01X657562Y557337D02*
X654672Y555388D01*
G01X658041Y556181D02*
X647305Y548943D01*
G01X688968Y563445D02*
X657562Y557337D01*
G01X688971Y562197D02*
X658041Y556181D01*
G01X707102Y560019D02*
X688968Y563445D01*
G01X706372Y558910D02*
X688971Y562197D01*
G01X708635Y557747D02*
X707102Y560019D01*
G01X707410Y557372D02*
X706372Y558910D01*
G01X708635Y555862D02*
Y557747D01*
G01X707410Y555861D02*
Y557372D01*
G01X709080Y554788D02*
G02X708635Y555862I1074J1074D01*
G01X708214Y553921D02*
G02X707410Y555861I1940J1941D01*
G01X709901Y553968D02*
X709080Y554788D01*
G01X709035Y553101D02*
X708214Y553921D01*
G01X709903Y553967D02*
X709901Y553969D01*
G01X709035Y553101D02*
X708214Y553921D01*
G01X658041Y556181D02*
X647305Y548943D01*
G01X651988Y553579D02*
X646422Y549826D01*
G01X654672Y555388D02*
X651988Y553579D01*
G01X657562Y557337D02*
X654672Y555388D01*
G01X688971Y562197D02*
X658041Y556181D01*
G01X688968Y563445D02*
X657562Y557337D01*
G01X706372Y558910D02*
X688971Y562197D01*
G01X707102Y560019D02*
X688968Y563445D01*
G01X707410Y557372D02*
X706372Y558910D01*
G01X708635Y557747D02*
X707102Y560019D01*
G01X707410Y555861D02*
Y557372D01*
G01X708635Y555862D02*
Y557747D01*
G01X708214Y553921D02*
G02X707410Y555861I1940J1941D01*
G01X709080Y554788D02*
G02X708635Y555862I1074J1074D01*
G01X709035Y553101D02*
X708214Y553921D01*
G01X709901Y553968D02*
X709080Y554788D01*
G01X709903Y553967D02*
X709901Y553969D01*
G01X654135Y561312D02*
X643141Y553897D01*
G01X654614Y560156D02*
X644024Y553014D01*
G01X689689Y568223D02*
X654135Y561312D01*
G01X689689Y566975D02*
X654614Y560156D01*
G01X719872Y562358D02*
X689689Y568223D01*
G01X719393Y561202D02*
X689689Y566975D01*
G01X654614Y560156D02*
X644024Y553014D01*
G01X654135Y561312D02*
X643141Y553897D01*
G01X689689Y566975D02*
X654614Y560156D01*
G01X689689Y568223D02*
X654135Y561312D01*
G01X719393Y561202D02*
X689689Y566975D01*
G01X719872Y562358D02*
X689689Y568223D01*
G01X695590Y573991D02*
X650554Y565238D01*
G01X695590Y572743D02*
X651033Y564082D01*
G01X695590Y572743D02*
X651033Y564082D01*
G01X695590Y573991D02*
X650554Y565238D01*
G01X656460Y575998D02*
X647272Y574214D01*
G01X657685Y574988D02*
X647751Y573058D01*
G01X701689Y584792D02*
X656460Y575999D01*
G01X701689Y583544D02*
X657685Y574989D01*
G01X726797Y579888D02*
X701690Y584793D01*
G01X801760Y563993D02*
X701689Y583544D01*
G01X801760Y563993D02*
X701689Y583544D01*
G01X801760Y563993D02*
X701689Y583544D01*
G01X657685Y574988D02*
X647751Y573058D01*
G01X656460Y575998D02*
X647272Y574214D01*
G01X701689Y583544D02*
X657685Y574989D01*
G01X701689Y584792D02*
X656460Y575999D01*
G01X801760Y563993D02*
X701689Y583544D01*
G01X726797Y579888D02*
X701690Y584793D01*
G01X706058Y590539D02*
X645179Y578708D01*
G01X706058Y589291D02*
X645658Y577552D01*
G01X805765Y571158D02*
X706058Y590539D01*
G01X805289Y570002D02*
X706058Y589291D01*
G01D02*
X645658Y577552D01*
G01X706058Y590539D02*
X645179Y578708D01*
G01X805289Y570002D02*
X706058Y589291D01*
G01X805765Y571158D02*
X706058Y590539D01*
G01X763589Y560778D02*
X695590Y573991D01*
G01X762987Y559646D02*
X695590Y572743D01*
G01X762987Y559646D02*
X695590Y572743D01*
G01X763589Y560778D02*
X695590Y573991D01*
G01X701574Y579858D02*
X648948Y569634D01*
G01X701574Y578610D02*
X649427Y568478D01*
G01X701807Y579813D02*
X701574Y579858D01*
G01Y578610D02*
X649427Y568478D01*
G01X783850Y562612D02*
X701574Y578610D01*
G01X784329Y563768D02*
X701807Y579813D01*
G01X783850Y562612D02*
X701574Y578610D01*
G01D02*
X649427Y568478D01*
G01X701574Y579858D02*
X648948Y569634D01*
G01X701807Y579813D02*
X701574Y579858D01*
G01X783850Y562612D02*
X701574Y578610D01*
G01X701807Y579813D02*
X701574Y579858D01*
G01X784329Y563768D02*
X701807Y579813D01*
G01X725603Y558491D02*
X719872Y562358D01*
G01X724820Y557541D02*
X719393Y561202D01*
G01X727905Y556189D02*
X725603Y558491D01*
G01X726565Y555796D02*
X724820Y557541D01*
G01X727038Y555322D02*
X726565Y555796D01*
G01X728600Y554511D02*
G03X727905Y556189I-2374J0D01*
G01X727375Y554510D02*
G03X727038Y555322I-1149J-1D01*
G01X728600Y554047D02*
Y554511D01*
G01X727375Y554048D02*
Y554510D01*
G01X729080Y552888D02*
G02X728600Y554047I1159J1159D01*
G01X728213Y552021D02*
G02X727375Y554048I2027J2025D01*
G01X729490Y552478D02*
X729080Y552888D01*
G01X729035Y551200D02*
X728213Y552021D01*
G01X729901Y552068D02*
X729490Y552478D01*
G01X729035Y551200D02*
X728213Y552021D01*
G01X729903Y552067D02*
X729901Y552069D01*
G01X729035Y551200D02*
X728213Y552021D01*
G01X724820Y557541D02*
X719393Y561202D01*
G01X725603Y558491D02*
X719872Y562358D01*
G01X726565Y555796D02*
X724820Y557541D01*
G01X727905Y556189D02*
X725603Y558491D01*
G01X727038Y555322D02*
X726565Y555796D01*
G01X727905Y556189D02*
X725603Y558491D01*
G01X727375Y554510D02*
G03X727038Y555322I-1149J-1D01*
G01X728600Y554511D02*
G03X727905Y556189I-2374J0D01*
G01X727375Y554048D02*
Y554510D01*
G01X728600Y554047D02*
Y554511D01*
G01X728213Y552021D02*
G02X727375Y554048I2027J2025D01*
G01X729080Y552888D02*
G02X728600Y554047I1159J1159D01*
G01X729035Y551200D02*
X728213Y552021D01*
G01X729490Y552478D02*
X729080Y552888D01*
G01X729901Y552068D02*
X729490Y552478D01*
G01X729903Y552067D02*
X729901Y552069D01*
G01X769483Y554884D02*
X763589Y560778D01*
G01X768616Y554017D02*
X762987Y559646D01*
G01X768616Y554017D02*
X762987Y559646D01*
G01X769483Y554884D02*
X763589Y560778D01*
G01X786471Y562322D02*
X784329Y563768D01*
G01X785688Y561372D02*
X783850Y562612D01*
G01X788000Y560793D02*
X786471Y562322D01*
G01X786775Y560285D02*
X785688Y561372D01*
G01D02*
X783850Y562612D01*
G01X786471Y562322D02*
X784329Y563768D01*
G01X786775Y560285D02*
X785688Y561372D01*
G01X788000Y560793D02*
X786471Y562322D01*
G01X764395Y572544D02*
X726797Y579888D01*
G01X802236Y565149D02*
X764395Y572542D01*
G01Y572544D02*
X726797Y579888D01*
G01X802236Y565149D02*
X764395Y572542D01*
G01X805858Y562737D02*
X802236Y565149D01*
G01X805077Y561784D02*
X801760Y563993D01*
G01X807161Y561433D02*
X805858Y562737D01*
G01X805936Y560925D02*
X805077Y561784D01*
G01X807161Y558183D02*
Y561433D01*
G01X805936Y558183D02*
Y560925D01*
G01X807498Y557369D02*
G02X807161Y558183I814J814D01*
G01X806632Y556502D02*
G02X805936Y558183I1680J1680D01*
G01X807982Y556885D02*
X807498Y557369D01*
G01X807039Y556095D02*
X806632Y556502D01*
G01X807116Y556017D02*
X807038Y556094D01*
G01X805077Y561784D02*
X801760Y563993D01*
G01X805858Y562737D02*
X802236Y565149D01*
G01X805936Y560925D02*
X805077Y561784D01*
G01X807161Y561433D02*
X805858Y562737D01*
G01X805936Y558183D02*
Y560925D01*
G01X807161Y558183D02*
Y561433D01*
G01X806632Y556502D02*
G02X805936Y558183I1680J1680D01*
G01X807498Y557369D02*
G02X807161Y558183I814J814D01*
G01X807039Y556095D02*
X806632Y556502D01*
G01X807982Y556885D02*
X807498Y557369D01*
G01X807116Y556017D02*
X807038Y556094D01*
G01X807982Y556885D02*
X807498Y557369D01*
G01X820711Y561156D02*
X805765Y571158D01*
G01X819929Y560204D02*
X805289Y570002D01*
G01X826483Y555384D02*
X820711Y561156D01*
G01X824795Y555338D02*
X819929Y560204D01*
G01X825616Y554518D02*
X824795Y555338D01*
G01X819929Y560204D02*
X805289Y570002D01*
G01X820711Y561156D02*
X805765Y571158D01*
G01X824795Y555338D02*
X819929Y560204D01*
G01X826483Y555384D02*
X820711Y561156D01*
G01X825616Y554518D02*
X824795Y555338D01*
G01X826483Y555384D02*
X820711Y561156D01*
G01X788000Y559200D02*
Y560793D01*
G01X786775Y559201D02*
Y560285D01*
G01X788589Y557776D02*
G02X788000Y559200I1424J1423D01*
G01X787722Y556910D02*
G02X786775Y559201I2292J2288D01*
G01X789483Y556884D02*
X788624Y557741D01*
G01X787794Y556838D02*
X787722Y556910D01*
G01X788616Y556017D02*
X787794Y556838D01*
G01X786775Y559201D02*
Y560285D01*
G01X788000Y559200D02*
Y560793D01*
G01X787722Y556910D02*
G02X786775Y559201I2292J2288D01*
G01X788589Y557776D02*
G02X788000Y559200I1424J1423D01*
G01X787794Y556838D02*
X787722Y556910D01*
G01X789483Y556884D02*
X788624Y557741D01*
G01X788616Y556017D02*
X787794Y556838D01*
G01X789483Y556884D02*
X788624Y557741D01*
M02*
